FILE_TYPE = MACRO_DRAWING;
SET COLOR_WIRE YELLOW;
SET COLOR_PROP ORANGE;
SET COLOR_DOT WHITE;
SET COLOR_ARC YELLOW;
SET COLOR_BODY GREEN;
SET COLOR_NOTE PURPLE;
SET PROP_DISPLAY VALUE;
SET PAGE_NUMBER P282;
FORCEADD OFFPAGE..1
(-7300 350);
FORCEPROP 2 LAST $XR1 297 
J 0
(-7672 350);
DISPLAY 0.638298 (-7672 350);
PAINT MONO (-7672 350);
FORCEPROP 2 LAST $XR0 296 
J 0
(-7552 350);
DISPLAY 0.638298 (-7552 350);
PAINT MONO (-7552 350);
FORCEPROP 1 LAST COMMENT_BODY TRUE
J 0
(-7175 250);
DISPLAY 0.872340 (-7175 250);
PAINT GREEN (-7175 250);
DISPLAY INVISIBLE (-7175 250);
FORCEPROP 1 LAST OFFPAGE TRUE
J 0
(-6975 225);
DISPLAY 0.872340 (-6975 225);
PAINT GREEN (-6975 225);
DISPLAY INVISIBLE (-6975 225);
FORCEPROP 2 LAST CDS_LIB standard
J 0
(-7300 350);
DISPLAY INVISIBLE (-7300 350);
FORCEPROP 2 LAST PATH I1
J 0
(-7550 400);
DISPLAY 1.021277 (-7550 400);
DISPLAY INVISIBLE (-7550 400);
FORCEADD Q_RES..1
(-5400 0);
FORCEPROP 1 LAST PART_NUMBER CS04992FB07
J 0
(-5500 -75);
DISPLAY 0.617021 (-5500 -75);
PAINT BLUE (-5500 -75);
DISPLAY INVISIBLE (-5500 -75);
FORCEPROP 1 LAST MATERIAL CHIP
J 0
(-5200 50);
DISPLAY 0.617021 (-5200 50);
PAINT SKYBLUE (-5200 50);
FORCEPROP 1 LAST VALUE 49.9
J 2
(-5150 0);
DISPLAY 0.617021 (-5150 0);
PAINT SKYBLUE (-5150 0);
FORCEPROP 1 LAST TOLERANCE 1%
J 0
(-5275 50);
DISPLAY 0.617021 (-5275 50);
PAINT SKYBLUE (-5275 50);
FORCEPROP 1 LAST PACK_TYPE 0402LF
J 0
(-5500 -125);
DISPLAY 0.617021 (-5500 -125);
PAINT SKYBLUE (-5500 -125);
FORCEPROP 1 LAST WATTAGE 1/16W
J 2
(-5200 -125);
DISPLAY 0.617021 (-5200 -125);
PAINT SKYBLUE (-5200 -125);
FORCEPROP 1 LAST LOCATION PR1410
J 0
(-5625 0);
DISPLAY 0.617021 (-5625 0);
PAINT AQUA (-5625 0);
FORCEPROP 1 LASTPIN (-5500 0) $PN 1
J 0
(-5488 12);
DISPLAY 0.617021 (-5488 12);
FORCEPROP 1 LASTPIN (-5300 0) $PN 2
J 0
(-5338 12);
DISPLAY 0.617021 (-5338 12);
FORCEPROP 2 LAST CDS_LIB pure_quanta
J 0
(-5400 0);
PAINT MONO (-5400 0);
DISPLAY INVISIBLE (-5400 0);
FORCEPROP 1 LAST PATH I10
J 0
(-5450 150);
DISPLAY 0.978723 (-5450 150);
PAINT WHITE (-5450 150);
DISPLAY INVISIBLE (-5450 150);
FORCEPROP 2 LAST $SEC 1
J 0
(-5450 200);
DISPLAY 0.680851 (-5450 200);
PAINT MONO (-5450 200);
DISPLAY INVISIBLE (-5450 200);
FORCEPROP 2 LAST CDS_SEC 1
J 0
(-5450 200);
DISPLAY 1.021277 (-5450 200);
DISPLAY INVISIBLE (-5450 200);
FORCEADD Q_RES..2
R 2
(-5000 -200);
FORCEPROP 1 LAST PART_NUMBER CS21002FB06
J 2
(-5040 -325);
DISPLAY 0.617021 (-5040 -325);
PAINT BLUE (-5040 -325);
DISPLAY INVISIBLE (-5040 -325);
FORCEPROP 1 LAST TOLERANCE 1%
J 2
(-5045 -175);
DISPLAY 0.617021 (-5045 -175);
PAINT SKYBLUE (-5045 -175);
FORCEPROP 1 LAST WATTAGE 1/16W
J 2
(-5040 -225);
DISPLAY 0.617021 (-5040 -225);
PAINT SKYBLUE (-5040 -225);
FORCEPROP 1 LAST MATERIAL EMPTY
J 2
(-5040 -275);
DISPLAY 0.617021 (-5040 -275);
PAINT RED (-5040 -275);
FORCEPROP 1 LAST VALUE 1K
J 2
(-5045 -125);
DISPLAY 0.617021 (-5045 -125);
PAINT SKYBLUE (-5045 -125);
FORCEPROP 1 LAST PACK_TYPE 0402LF
J 2
(-5040 -375);
DISPLAY 0.617021 (-5040 -375);
PAINT SKYBLUE (-5040 -375);
FORCEPROP 1 LAST LOCATION PR214
J 2
(-5045 -75);
DISPLAY 0.617021 (-5045 -75);
PAINT AQUA (-5045 -75);
FORCEPROP 1 LASTPIN (-5000 -100) $PN 1
J 2
(-5005 -138);
DISPLAY 0.617021 (-5005 -138);
PAINT MONO (-5005 -138);
FORCEPROP 1 LASTPIN (-5000 -300) $PN 2
J 2
(-5005 -290);
DISPLAY 0.617021 (-5005 -290);
PAINT MONO (-5005 -290);
FORCEPROP 2 LAST CDS_LIB pure_quanta
J 2
(-5000 -200);
DISPLAY INVISIBLE (-5000 -200);
FORCEPROP 1 LAST PATH I11
J 2
(-5050 -25);
DISPLAY 0.978723 (-5050 -25);
PAINT WHITE (-5050 -25);
DISPLAY INVISIBLE (-5050 -25);
FORCEPROP 1 LAST LOCATION PR214
J 2
(-5050 -25);
DISPLAY 1.021277 (-5050 -25);
PAINT AQUA (-5050 -25);
DISPLAY INVISIBLE (-5050 -25);
FORCEPROP 0 LAST $SEC 1
J 2
(-5050 -25);
DISPLAY 0.680851 (-5050 -25);
PAINT MONO (-5050 -25);
DISPLAY INVISIBLE (-5050 -25);
FORCEPROP 0 LAST CDS_SEC 1
J 2
(-5050 -25);
DISPLAY 1.021277 (-5050 -25);
DISPLAY INVISIBLE (-5050 -25);
FORCEADD UNIVERSAL_GND..1
(-4875 -500);
FORCEPROP 3 LASTPIN (-4875 -450) SIG_NAME GND\g
J 0
(-4865 -440);
DISPLAY 0.659574 (-4865 -440);
PAINT MONO (-4865 -440);
DISPLAY INVISIBLE (-4865 -440);
FORCEPROP 1 LAST HDL_POWER GND
J 1
(-4850 -575);
DISPLAY 0.872340 (-4850 -575);
PAINT GREEN (-4850 -575);
DISPLAY INVISIBLE (-4850 -575);
FORCEPROP 2 LAST CDS_LIB logical_power
J 0
(-4875 -500);
PAINT MONO (-4875 -500);
DISPLAY INVISIBLE (-4875 -500);
FORCEPROP 1 LAST PATH I12
J 0
(-4800 -500);
DISPLAY 0.872340 (-4800 -500);
PAINT AQUA (-4800 -500);
DISPLAY INVISIBLE (-4800 -500);
FORCEADD Q_CAP..1
(-4875 -200);
FORCEPROP 1 LAST PART_NUMBER CH4104K1B00
J 0
(-4825 -375);
DISPLAY 0.617021 (-4825 -375);
PAINT BLUE (-4825 -375);
DISPLAY INVISIBLE (-4825 -375);
FORCEPROP 1 LAST VOLTAGE 25V
J 0
(-4825 -175);
DISPLAY 0.617021 (-4825 -175);
PAINT SKYBLUE (-4825 -175);
FORCEPROP 1 LAST VALUE 0.1UF
J 0
(-4825 -125);
DISPLAY 0.617021 (-4825 -125);
PAINT SKYBLUE (-4825 -125);
FORCEPROP 1 LAST TOLERANCE 10%
J 0
(-4825 -225);
DISPLAY 0.617021 (-4825 -225);
PAINT SKYBLUE (-4825 -225);
FORCEPROP 1 LAST MATERIAL X7R
J 0
(-4825 -275);
DISPLAY 0.617021 (-4825 -275);
PAINT SKYBLUE (-4825 -275);
FORCEPROP 1 LAST PACK_TYPE 0402
J 0
(-4825 -325);
DISPLAY 0.617021 (-4825 -325);
PAINT SKYBLUE (-4825 -325);
FORCEPROP 1 LAST LOCATION PC386
J 0
(-4825 -75);
DISPLAY 0.617021 (-4825 -75);
PAINT AQUA (-4825 -75);
FORCEPROP 1 LASTPIN (-4875 -100) $PN 1
J 0
(-4865 -120);
DISPLAY 0.617021 (-4865 -120);
PAINT MONO (-4865 -120);
FORCEPROP 1 LASTPIN (-4875 -300) $PN 2
J 0
(-4865 -320);
DISPLAY 0.617021 (-4865 -320);
PAINT MONO (-4865 -320);
FORCEPROP 2 LAST CDS_LIB pure_quanta
J 0
(-4875 -200);
DISPLAY INVISIBLE (-4875 -200);
FORCEPROP 1 LAST PATH I13
J 0
(-4825 -50);
DISPLAY 0.978723 (-4825 -50);
PAINT WHITE (-4825 -50);
DISPLAY INVISIBLE (-4825 -50);
FORCEPROP 1 LAST LOCATION PC386
J 0
(-4825 -25);
DISPLAY 1.021277 (-4825 -25);
PAINT AQUA (-4825 -25);
DISPLAY INVISIBLE (-4825 -25);
FORCEPROP 0 LAST $SEC 1
J 0
(-4825 -25);
DISPLAY 0.680851 (-4825 -25);
PAINT MONO (-4825 -25);
DISPLAY INVISIBLE (-4825 -25);
FORCEPROP 0 LAST CDS_SEC 1
J 0
(-4825 -25);
DISPLAY 1.021277 (-4825 -25);
DISPLAY INVISIBLE (-4825 -25);
FORCEADD OFFPAGE..5
(-5225 1200);
FORCEPROP 1 LAST COMMENT_BODY TRUE
J 0
(-5125 1125);
DISPLAY 0.872340 (-5125 1125);
PAINT GREEN (-5125 1125);
DISPLAY INVISIBLE (-5125 1125);
FORCEPROP 1 LAST OFFPAGE TRUE
J 0
(-4900 1075);
DISPLAY 0.872340 (-4900 1075);
PAINT GREEN (-4900 1075);
DISPLAY INVISIBLE (-4900 1075);
FORCEPROP 2 LAST CDS_LIB standard
J 0
(-5225 1200);
DISPLAY INVISIBLE (-5225 1200);
FORCEPROP 2 LAST PATH I14
J 0
(-5175 1275);
DISPLAY 1.021277 (-5175 1275);
DISPLAY INVISIBLE (-5175 1275);
FORCEADD Q_RES..1
(-5975 2925);
FORCEPROP 1 LAST PART_NUMBER CS11002FB07
J 0
(-5850 2975);
DISPLAY 0.617021 (-5850 2975);
PAINT BLUE (-5850 2975);
DISPLAY INVISIBLE (-5850 2975);
FORCEPROP 1 LAST WATTAGE 1/16W
J 2
(-5550 3025);
DISPLAY 0.617021 (-5550 3025);
PAINT SKYBLUE (-5550 3025);
FORCEPROP 1 LAST MATERIAL CHIP
J 0
(-5850 3025);
DISPLAY 0.617021 (-5850 3025);
PAINT SKYBLUE (-5850 3025);
FORCEPROP 1 LAST TOLERANCE 1%
J 0
(-5750 2925);
DISPLAY 0.617021 (-5750 2925);
PAINT SKYBLUE (-5750 2925);
FORCEPROP 1 LAST VALUE 100
J 2
(-5775 2925);
DISPLAY 0.617021 (-5775 2925);
PAINT SKYBLUE (-5775 2925);
FORCEPROP 1 LAST PACK_TYPE 0402LF
J 0
(-5675 2925);
DISPLAY 0.617021 (-5675 2925);
PAINT SKYBLUE (-5675 2925);
FORCEPROP 1 LAST LOCATION PR558
J 0
(-6225 2925);
DISPLAY 0.617021 (-6225 2925);
PAINT AQUA (-6225 2925);
FORCEPROP 1 LASTPIN (-6075 2925) $PN 1
J 0
(-6063 2937);
DISPLAY 0.617021 (-6063 2937);
FORCEPROP 1 LASTPIN (-5875 2925) $PN 2
J 0
(-5913 2937);
DISPLAY 0.617021 (-5913 2937);
FORCEPROP 2 LAST CDS_LIB pure_quanta
J 0
(-5975 2925);
PAINT MONO (-5975 2925);
DISPLAY INVISIBLE (-5975 2925);
FORCEPROP 1 LAST PATH I15
J 0
(-6025 3075);
DISPLAY 0.978723 (-6025 3075);
PAINT WHITE (-6025 3075);
DISPLAY INVISIBLE (-6025 3075);
FORCEPROP 2 LAST $SEC 1
J 0
(-6025 3125);
DISPLAY 0.680851 (-6025 3125);
PAINT MONO (-6025 3125);
DISPLAY INVISIBLE (-6025 3125);
FORCEPROP 2 LAST CDS_SEC 1
J 0
(-6025 3125);
DISPLAY 1.021277 (-6025 3125);
DISPLAY INVISIBLE (-6025 3125);
FORCEADD Q_SHORT..1
(-6025 3450);
FORCEPROP 1 LAST PART_NUMBER SHORT6
J 0
(-6000 3210);
DISPLAY 0.617021 (-6000 3210);
PAINT BLUE (-6000 3210);
DISPLAY INVISIBLE (-6000 3210);
FORCEPROP 2 LAST PACK_TYPE SM
J 0
(-6000 3300);
DISPLAY 0.617021 (-6000 3300);
PAINT SKYBLUE (-6000 3300);
FORCEPROP 1 LAST MATERIAL EMPTY
J 0
(-6000 3260);
DISPLAY 0.617021 (-6000 3260);
PAINT RED (-6000 3260);
FORCEPROP 1 LAST LOCATION PJ48
J 0
(-6125 3305);
DISPLAY 0.617021 (-6125 3305);
PAINT AQUA (-6125 3305);
FORCEPROP 0 LASTPIN (-6150 3450) $PN 1
J 2
(-6160 3460);
DISPLAY 0.617021 (-6160 3460);
PAINT MONO (-6160 3460);
FORCEPROP 0 LASTPIN (-5900 3450) $PN 2
J 0
(-5890 3460);
DISPLAY 0.617021 (-5890 3460);
PAINT MONO (-5890 3460);
FORCEPROP 2 LAST CDS_LIB pure_quanta
J 0
(-6025 3450);
DISPLAY INVISIBLE (-6025 3450);
FORCEPROP 1 LAST NEEDS_NO_SIZE TRUE
J 0
(-6025 3450);
DISPLAY 0.468085 (-6025 3450);
PAINT GREEN (-6025 3450);
DISPLAY INVISIBLE (-6025 3450);
FORCEPROP 1 LAST PATH I16
J 0
(-6100 3655);
DISPLAY 0.723404 (-6100 3655);
PAINT GREEN (-6100 3655);
DISPLAY INVISIBLE (-6100 3655);
FORCEPROP 1 LAST LOCATION PJ48
J 0
(-6100 3700);
DISPLAY 1.021277 (-6100 3700);
PAINT AQUA (-6100 3700);
DISPLAY INVISIBLE (-6100 3700);
FORCEPROP 0 LAST $SEC 1
J 0
(-6100 3700);
DISPLAY 0.680851 (-6100 3700);
PAINT MONO (-6100 3700);
DISPLAY INVISIBLE (-6100 3700);
FORCEPROP 0 LAST CDS_SEC 1
J 0
(-6100 3700);
DISPLAY 1.021277 (-6100 3700);
DISPLAY INVISIBLE (-6100 3700);
FORCEADD UNIVERSAL_GND..1
(-5450 2825);
FORCEPROP 3 LASTPIN (-5450 2875) SIG_NAME GND\g
J 0
(-5440 2885);
DISPLAY 0.659574 (-5440 2885);
PAINT MONO (-5440 2885);
DISPLAY INVISIBLE (-5440 2885);
FORCEPROP 1 LAST HDL_POWER GND
J 1
(-5425 2750);
DISPLAY 0.872340 (-5425 2750);
PAINT GREEN (-5425 2750);
DISPLAY INVISIBLE (-5425 2750);
FORCEPROP 2 LAST CDS_LIB logical_power
J 0
(-5450 2825);
PAINT MONO (-5450 2825);
DISPLAY INVISIBLE (-5450 2825);
FORCEPROP 1 LAST PATH I17
J 0
(-5375 2825);
DISPLAY 0.872340 (-5375 2825);
PAINT AQUA (-5375 2825);
DISPLAY INVISIBLE (-5375 2825);
FORCEADD Q_RES..2
(-5075 1750);
FORCEPROP 1 LAST PART_NUMBER CS21002FB06
J 0
(-5050 1625);
DISPLAY 0.617021 (-5050 1625);
PAINT BLUE (-5050 1625);
DISPLAY INVISIBLE (-5050 1625);
FORCEPROP 1 LAST VALUE 1K
J 0
(-5045 1825);
DISPLAY 0.617021 (-5045 1825);
PAINT SKYBLUE (-5045 1825);
FORCEPROP 1 LAST WATTAGE 1/16W
J 0
(-5050 1725);
DISPLAY 0.617021 (-5050 1725);
PAINT SKYBLUE (-5050 1725);
FORCEPROP 1 LAST TOLERANCE 1%
J 0
(-5045 1775);
DISPLAY 0.617021 (-5045 1775);
PAINT SKYBLUE (-5045 1775);
FORCEPROP 1 LAST MATERIAL CHIP
J 0
(-5050 1675);
DISPLAY 0.617021 (-5050 1675);
PAINT SKYBLUE (-5050 1675);
FORCEPROP 1 LAST PACK_TYPE 0402LF
J 0
(-5050 1575);
DISPLAY 0.617021 (-5050 1575);
PAINT SKYBLUE (-5050 1575);
FORCEPROP 1 LAST LOCATION PR215
J 0
(-5050 1875);
DISPLAY 0.617021 (-5050 1875);
PAINT AQUA (-5050 1875);
FORCEPROP 1 LASTPIN (-5075 1850) $PN 1
J 0
(-5070 1812);
DISPLAY 0.617021 (-5070 1812);
PAINT MONO (-5070 1812);
FORCEPROP 1 LASTPIN (-5075 1650) $PN 2
J 0
(-5070 1660);
DISPLAY 0.617021 (-5070 1660);
PAINT MONO (-5070 1660);
FORCEPROP 2 LAST CDS_LIB pure_quanta
J 0
(-5075 1750);
DISPLAY INVISIBLE (-5075 1750);
FORCEPROP 1 LAST PATH I18
J 0
(-5025 1925);
DISPLAY 0.978723 (-5025 1925);
PAINT WHITE (-5025 1925);
DISPLAY INVISIBLE (-5025 1925);
FORCEPROP 1 LAST LOCATION PR215
J 0
(-5050 1925);
DISPLAY 1.021277 (-5050 1925);
PAINT AQUA (-5050 1925);
DISPLAY INVISIBLE (-5050 1925);
FORCEPROP 0 LAST $SEC 1
J 0
(-5050 1925);
DISPLAY 0.680851 (-5050 1925);
PAINT MONO (-5050 1925);
DISPLAY INVISIBLE (-5050 1925);
FORCEPROP 0 LAST CDS_SEC 1
J 0
(-5050 1925);
DISPLAY 1.021277 (-5050 1925);
DISPLAY INVISIBLE (-5050 1925);
FORCEADD VCC15..1
(-5075 2100);
FORCEPROP 3 LASTPIN (-5075 2050) SIG_NAME P3V3_AUX\g
J 0
(-5065 2060);
DISPLAY 0.659574 (-5065 2060);
PAINT MONO (-5065 2060);
DISPLAY INVISIBLE (-5065 2060);
FORCEPROP 1 LAST HDL_POWER P3V3_AUX
J 1
(-5075 2150);
DISPLAY 0.617021 (-5075 2150);
PAINT GREEN (-5075 2150);
FORCEPROP 2 LAST CDS_LIB logical_power
J 0
(-5075 2100);
DISPLAY INVISIBLE (-5075 2100);
FORCEPROP 1 LAST PATH I19
J 0
(-5025 2125);
DISPLAY 0.872340 (-5025 2125);
PAINT AQUA (-5025 2125);
DISPLAY INVISIBLE (-5025 2125);
FORCEADD OFFPAGE..1
(-6800 0);
FORCEPROP 2 LAST $XR0 251 
J 0
(-7052 0);
DISPLAY 0.638298 (-7052 0);
PAINT MONO (-7052 0);
FORCEPROP 1 LAST COMMENT_BODY TRUE
J 0
(-6675 -100);
DISPLAY 0.872340 (-6675 -100);
PAINT GREEN (-6675 -100);
DISPLAY INVISIBLE (-6675 -100);
FORCEPROP 1 LAST OFFPAGE TRUE
J 0
(-6475 -125);
DISPLAY 0.872340 (-6475 -125);
PAINT GREEN (-6475 -125);
DISPLAY INVISIBLE (-6475 -125);
FORCEPROP 2 LAST CDS_LIB standard
J 0
(-6800 0);
PAINT MONO (-6800 0);
DISPLAY INVISIBLE (-6800 0);
FORCEPROP 2 LAST PATH I2
J 0
(-7050 50);
DISPLAY 1.021277 (-7050 50);
DISPLAY INVISIBLE (-7050 50);
FORCEADD Q_RES..2
(-4750 1750);
FORCEPROP 1 LAST PART_NUMBER CS21002FB06
J 0
(-4725 1625);
DISPLAY 0.617021 (-4725 1625);
PAINT BLUE (-4725 1625);
DISPLAY INVISIBLE (-4725 1625);
FORCEPROP 1 LAST TOLERANCE 1%
J 0
(-4720 1775);
DISPLAY 0.617021 (-4720 1775);
PAINT SKYBLUE (-4720 1775);
FORCEPROP 1 LAST VALUE 1K
J 0
(-4720 1825);
DISPLAY 0.617021 (-4720 1825);
PAINT SKYBLUE (-4720 1825);
FORCEPROP 1 LAST MATERIAL CHIP
J 0
(-4725 1675);
DISPLAY 0.617021 (-4725 1675);
PAINT SKYBLUE (-4725 1675);
FORCEPROP 1 LAST PACK_TYPE 0402LF
J 0
(-4725 1575);
DISPLAY 0.617021 (-4725 1575);
PAINT SKYBLUE (-4725 1575);
FORCEPROP 1 LAST WATTAGE 1/16W
J 0
(-4725 1725);
DISPLAY 0.617021 (-4725 1725);
PAINT SKYBLUE (-4725 1725);
FORCEPROP 1 LAST LOCATION PR217
J 0
(-4725 1875);
DISPLAY 0.617021 (-4725 1875);
PAINT AQUA (-4725 1875);
FORCEPROP 1 LASTPIN (-4750 1850) $PN 1
J 0
(-4745 1812);
DISPLAY 0.617021 (-4745 1812);
PAINT MONO (-4745 1812);
FORCEPROP 1 LASTPIN (-4750 1650) $PN 2
J 0
(-4745 1660);
DISPLAY 0.617021 (-4745 1660);
PAINT MONO (-4745 1660);
FORCEPROP 2 LAST CDS_LIB pure_quanta
J 0
(-4750 1750);
DISPLAY INVISIBLE (-4750 1750);
FORCEPROP 1 LAST PATH I20
J 0
(-4700 1925);
DISPLAY 0.978723 (-4700 1925);
PAINT WHITE (-4700 1925);
DISPLAY INVISIBLE (-4700 1925);
FORCEPROP 1 LAST LOCATION PR217
J 0
(-4725 1925);
DISPLAY 1.021277 (-4725 1925);
PAINT AQUA (-4725 1925);
DISPLAY INVISIBLE (-4725 1925);
FORCEPROP 0 LAST $SEC 1
J 0
(-4725 1925);
DISPLAY 0.680851 (-4725 1925);
PAINT MONO (-4725 1925);
DISPLAY INVISIBLE (-4725 1925);
FORCEPROP 0 LAST CDS_SEC 1
J 0
(-4725 1925);
DISPLAY 1.021277 (-4725 1925);
DISPLAY INVISIBLE (-4725 1925);
FORCEADD Q_RES..1
(-4925 3450);
FORCEPROP 1 LAST PART_NUMBER CS00002JB13
J 0
(-4800 3500);
DISPLAY 0.617021 (-4800 3500);
PAINT BLUE (-4800 3500);
DISPLAY INVISIBLE (-4800 3500);
FORCEPROP 1 LAST TOLERANCE 5%
J 0
(-4750 3450);
DISPLAY 0.617021 (-4750 3450);
PAINT SKYBLUE (-4750 3450);
FORCEPROP 1 LAST PACK_TYPE 0402LF
J 0
(-4675 3450);
DISPLAY 0.617021 (-4675 3450);
PAINT SKYBLUE (-4675 3450);
FORCEPROP 1 LAST VALUE 0
J 2
(-4775 3450);
DISPLAY 0.617021 (-4775 3450);
PAINT SKYBLUE (-4775 3450);
FORCEPROP 1 LAST WATTAGE 1/16W
J 2
(-4500 3550);
DISPLAY 0.617021 (-4500 3550);
PAINT SKYBLUE (-4500 3550);
FORCEPROP 1 LAST MATERIAL CHIP
J 0
(-4800 3550);
DISPLAY 0.617021 (-4800 3550);
PAINT SKYBLUE (-4800 3550);
FORCEPROP 1 LAST LOCATION PR216
J 0
(-5125 3450);
DISPLAY 0.617021 (-5125 3450);
PAINT AQUA (-5125 3450);
FORCEPROP 1 LASTPIN (-5025 3450) $PN 1
J 0
(-5013 3462);
DISPLAY 0.617021 (-5013 3462);
PAINT MONO (-5013 3462);
FORCEPROP 1 LASTPIN (-4825 3450) $PN 2
J 0
(-4863 3462);
DISPLAY 0.617021 (-4863 3462);
PAINT MONO (-4863 3462);
FORCEPROP 2 LAST CDS_LIB pure_quanta
J 0
(-4925 3450);
DISPLAY INVISIBLE (-4925 3450);
FORCEPROP 1 LAST PATH I21
J 0
(-4975 3600);
DISPLAY 0.978723 (-4975 3600);
PAINT WHITE (-4975 3600);
DISPLAY INVISIBLE (-4975 3600);
FORCEPROP 1 LAST LOCATION PR216
J 0
(-4975 3550);
DISPLAY 1.021277 (-4975 3550);
PAINT AQUA (-4975 3550);
DISPLAY INVISIBLE (-4975 3550);
FORCEPROP 0 LAST $SEC 1
J 0
(-4975 3550);
DISPLAY 0.680851 (-4975 3550);
PAINT MONO (-4975 3550);
DISPLAY INVISIBLE (-4975 3550);
FORCEPROP 0 LAST CDS_SEC 1
J 0
(-4975 3550);
DISPLAY 1.021277 (-4975 3550);
DISPLAY INVISIBLE (-4975 3550);
FORCEADD Q_CAP..1
(-4475 3275);
FORCEPROP 1 LAST PART_NUMBER TMP_QCH2336K1B12
J 0
(-4425 3100);
DISPLAY 0.617021 (-4425 3100);
PAINT BLUE (-4425 3100);
DISPLAY INVISIBLE (-4425 3100);
FORCEPROP 1 LAST PACK_TYPE 0402
J 0
(-4425 3150);
DISPLAY 0.617021 (-4425 3150);
PAINT SKYBLUE (-4425 3150);
FORCEPROP 1 LAST MATERIAL X7R
J 0
(-4425 3200);
DISPLAY 0.617021 (-4425 3200);
PAINT SKYBLUE (-4425 3200);
FORCEPROP 1 LAST TOLERANCE 10%
J 0
(-4425 3250);
DISPLAY 0.617021 (-4425 3250);
PAINT SKYBLUE (-4425 3250);
FORCEPROP 1 LAST VOLTAGE 50V
J 0
(-4425 3300);
DISPLAY 0.617021 (-4425 3300);
PAINT SKYBLUE (-4425 3300);
FORCEPROP 1 LAST VALUE 3300PF
J 0
(-4425 3350);
DISPLAY 0.617021 (-4425 3350);
PAINT SKYBLUE (-4425 3350);
FORCEPROP 1 LAST LOCATION PC389
J 0
(-4425 3400);
DISPLAY 0.617021 (-4425 3400);
PAINT AQUA (-4425 3400);
FORCEPROP 1 LASTPIN (-4475 3375) $PN 1
J 0
(-4465 3355);
DISPLAY 0.617021 (-4465 3355);
PAINT MONO (-4465 3355);
FORCEPROP 1 LASTPIN (-4475 3175) $PN 2
J 0
(-4465 3155);
DISPLAY 0.617021 (-4465 3155);
PAINT MONO (-4465 3155);
FORCEPROP 2 LAST CDS_LIB pure_quanta
J 0
(-4475 3275);
DISPLAY INVISIBLE (-4475 3275);
FORCEPROP 1 LAST PATH I22
J 0
(-4425 3425);
DISPLAY 0.978723 (-4425 3425);
PAINT WHITE (-4425 3425);
DISPLAY INVISIBLE (-4425 3425);
FORCEPROP 1 LAST LOCATION PC389
J 0
(-4425 3400);
DISPLAY 1.021277 (-4425 3400);
PAINT AQUA (-4425 3400);
DISPLAY INVISIBLE (-4425 3400);
FORCEPROP 0 LAST $SEC 1
J 0
(-4425 3400);
DISPLAY 0.680851 (-4425 3400);
PAINT MONO (-4425 3400);
DISPLAY INVISIBLE (-4425 3400);
FORCEPROP 0 LAST CDS_SEC 1
J 0
(-4425 3400);
DISPLAY 1.021277 (-4425 3400);
DISPLAY INVISIBLE (-4425 3400);
FORCEADD UNIVERSAL_GND..1
(-7550 4825);
FORCEPROP 3 LASTPIN (-7550 4875) SIG_NAME GND\g
J 0
(-7540 4885);
DISPLAY 0.659574 (-7540 4885);
PAINT MONO (-7540 4885);
DISPLAY INVISIBLE (-7540 4885);
FORCEPROP 1 LAST HDL_POWER GND
J 1
(-7525 4750);
DISPLAY 0.872340 (-7525 4750);
PAINT GREEN (-7525 4750);
DISPLAY INVISIBLE (-7525 4750);
FORCEPROP 2 LAST CDS_LIB logical_power
J 0
(-7550 4825);
PAINT MONO (-7550 4825);
DISPLAY INVISIBLE (-7550 4825);
FORCEPROP 1 LAST PATH I23
J 0
(-7475 4825);
DISPLAY 0.872340 (-7475 4825);
PAINT AQUA (-7475 4825);
DISPLAY INVISIBLE (-7475 4825);
FORCEADD Q_CAP..1
(-7550 5175);
FORCEPROP 1 LAST PART_NUMBER CH6101MEB03
J 0
(-7500 5025);
DISPLAY 0.617021 (-7500 5025);
PAINT BLUE (-7500 5025);
DISPLAY INVISIBLE (-7500 5025);
FORCEPROP 1 LAST VALUE 10UF
J 0
(-7500 5225);
DISPLAY 0.617021 (-7500 5225);
PAINT SKYBLUE (-7500 5225);
FORCEPROP 1 LAST VOLTAGE 6.3V
J 0
(-7500 5175);
DISPLAY 0.617021 (-7500 5175);
PAINT SKYBLUE (-7500 5175);
FORCEPROP 1 LAST TOLERANCE 20%
J 0
(-7500 5125);
DISPLAY 0.617021 (-7500 5125);
PAINT SKYBLUE (-7500 5125);
FORCEPROP 1 LAST MATERIAL X6S
J 0
(-7500 5075);
DISPLAY 0.617021 (-7500 5075);
PAINT SKYBLUE (-7500 5075);
FORCEPROP 1 LAST PACK_TYPE C0402
J 0
(-7500 4975);
DISPLAY 0.617021 (-7500 4975);
PAINT SKYBLUE (-7500 4975);
FORCEPROP 1 LAST LOCATION C1336
J 0
(-7500 5275);
DISPLAY 0.617021 (-7500 5275);
PAINT AQUA (-7500 5275);
FORCEPROP 1 LASTPIN (-7550 5275) $PN 1
J 0
(-7540 5255);
DISPLAY 0.617021 (-7540 5255);
FORCEPROP 1 LASTPIN (-7550 5075) $PN 2
J 0
(-7540 5055);
DISPLAY 0.617021 (-7540 5055);
FORCEPROP 2 LAST CDS_LIB pure_quanta
J 0
(-7550 5175);
PAINT MONO (-7550 5175);
DISPLAY INVISIBLE (-7550 5175);
FORCEPROP 1 LAST PATH I24
J 0
(-7500 5325);
DISPLAY 0.978723 (-7500 5325);
PAINT WHITE (-7500 5325);
DISPLAY INVISIBLE (-7500 5325);
FORCEPROP 2 LAST $SEC 1
J 0
(-7500 5375);
DISPLAY 0.680851 (-7500 5375);
PAINT MONO (-7500 5375);
DISPLAY INVISIBLE (-7500 5375);
FORCEPROP 2 LAST CDS_SEC 1
J 0
(-7500 5375);
DISPLAY 1.021277 (-7500 5375);
DISPLAY INVISIBLE (-7500 5375);
FORCEADD VCC15..1
(-7550 5450);
FORCEPROP 3 LASTPIN (-7550 5400) SIG_NAME PVNN_TERM_CPU1\g
J 0
(-7540 5410);
DISPLAY 0.659574 (-7540 5410);
PAINT MONO (-7540 5410);
DISPLAY INVISIBLE (-7540 5410);
FORCEPROP 1 LAST HDL_POWER PVNN_TERM_CPU1
J 1
(-7550 5500);
DISPLAY 0.617021 (-7550 5500);
PAINT GREEN (-7550 5500);
FORCEPROP 2 LAST CDS_LIB logical_power
J 0
(-7550 5450);
PAINT MONO (-7550 5450);
DISPLAY INVISIBLE (-7550 5450);
FORCEPROP 1 LAST PATH I25
J 0
(-7500 5475);
DISPLAY 0.872340 (-7500 5475);
PAINT AQUA (-7500 5475);
DISPLAY INVISIBLE (-7500 5475);
FORCEADD OFFPAGE..1
(-6675 4300);
FORCEPROP 2 LAST $XR1 292 
J 0
(-7047 4300);
DISPLAY 0.638298 (-7047 4300);
PAINT MONO (-7047 4300);
FORCEPROP 2 LAST $XR0 241 
J 0
(-6927 4300);
DISPLAY 0.638298 (-6927 4300);
PAINT MONO (-6927 4300);
FORCEPROP 1 LAST COMMENT_BODY TRUE
J 0
(-6550 4200);
DISPLAY 0.872340 (-6550 4200);
PAINT GREEN (-6550 4200);
DISPLAY INVISIBLE (-6550 4200);
FORCEPROP 1 LAST OFFPAGE TRUE
J 0
(-6350 4175);
DISPLAY 0.872340 (-6350 4175);
PAINT GREEN (-6350 4175);
DISPLAY INVISIBLE (-6350 4175);
FORCEPROP 2 LAST CDS_LIB standard
J 0
(-6675 4300);
DISPLAY INVISIBLE (-6675 4300);
FORCEPROP 2 LAST PATH I26
J 0
(-6925 4350);
DISPLAY 1.021277 (-6925 4350);
DISPLAY INVISIBLE (-6925 4350);
FORCEADD OFFPAGE..6
(-6675 4150);
FORCEPROP 2 LAST $XR1 292 
J 0
(-7105 4150);
DISPLAY 0.638298 (-7105 4150);
PAINT MONO (-7105 4150);
FORCEPROP 2 LAST $XR0 241 
J 0
(-6985 4150);
DISPLAY 0.638298 (-6985 4150);
PAINT MONO (-6985 4150);
FORCEPROP 1 LAST COMMENT_BODY TRUE
J 0
(-6575 4075);
DISPLAY 0.872340 (-6575 4075);
PAINT GREEN (-6575 4075);
DISPLAY INVISIBLE (-6575 4075);
FORCEPROP 1 LAST OFFPAGE TRUE
J 0
(-6350 4025);
DISPLAY 0.872340 (-6350 4025);
PAINT GREEN (-6350 4025);
DISPLAY INVISIBLE (-6350 4025);
FORCEPROP 2 LAST CDS_LIB standard
J 0
(-6675 4150);
DISPLAY INVISIBLE (-6675 4150);
FORCEPROP 2 LAST PATH I27
J 0
(-6975 4200);
DISPLAY 1.021277 (-6975 4200);
DISPLAY INVISIBLE (-6975 4200);
FORCEADD Q_CAP..1
(-7325 5175);
FORCEPROP 1 LAST PART_NUMBER CH4104K1B00
J 0
(-7275 4975);
DISPLAY 0.617021 (-7275 4975);
PAINT BLUE (-7275 4975);
DISPLAY INVISIBLE (-7275 4975);
FORCEPROP 1 LAST VOLTAGE 25V
J 0
(-7275 5175);
DISPLAY 0.617021 (-7275 5175);
PAINT SKYBLUE (-7275 5175);
FORCEPROP 1 LAST TOLERANCE 10%
J 0
(-7275 5125);
DISPLAY 0.617021 (-7275 5125);
PAINT SKYBLUE (-7275 5125);
FORCEPROP 1 LAST MATERIAL X7R
J 0
(-7275 5075);
DISPLAY 0.617021 (-7275 5075);
PAINT SKYBLUE (-7275 5075);
FORCEPROP 1 LAST VALUE 0.1UF
J 0
(-7275 5225);
DISPLAY 0.617021 (-7275 5225);
PAINT SKYBLUE (-7275 5225);
FORCEPROP 1 LAST PACK_TYPE 0402
J 0
(-7275 4925);
DISPLAY 0.617021 (-7275 4925);
PAINT SKYBLUE (-7275 4925);
FORCEPROP 1 LAST LOCATION C1337
J 0
(-7275 5275);
DISPLAY 0.617021 (-7275 5275);
PAINT AQUA (-7275 5275);
FORCEPROP 1 LASTPIN (-7325 5275) $PN 1
J 0
(-7315 5255);
DISPLAY 0.617021 (-7315 5255);
FORCEPROP 1 LASTPIN (-7325 5075) $PN 2
J 0
(-7315 5055);
DISPLAY 0.617021 (-7315 5055);
FORCEPROP 2 LAST CDS_LIB pure_quanta
J 0
(-7325 5175);
PAINT MONO (-7325 5175);
DISPLAY INVISIBLE (-7325 5175);
FORCEPROP 1 LAST PATH I28
J 0
(-7275 5325);
DISPLAY 0.978723 (-7275 5325);
PAINT WHITE (-7275 5325);
DISPLAY INVISIBLE (-7275 5325);
FORCEPROP 2 LAST $SEC 1
J 0
(-7275 5375);
DISPLAY 0.680851 (-7275 5375);
PAINT MONO (-7275 5375);
DISPLAY INVISIBLE (-7275 5375);
FORCEPROP 2 LAST CDS_SEC 1
J 0
(-7275 5375);
DISPLAY 1.021277 (-7275 5375);
DISPLAY INVISIBLE (-7275 5375);
FORCEADD Q_RES..1
(-6800 5075);
FORCEPROP 1 LAST PART_NUMBER CS11002FB07
J 0
(-6950 5000);
DISPLAY 0.510638 (-6950 5000);
DISPLAY INVISIBLE (-6950 5000);
FORCEPROP 1 LAST MATERIAL CHIP
J 0
(-6475 5075);
DISPLAY 0.638298 (-6475 5075);
FORCEPROP 1 LAST TOLERANCE 1%
J 0
(-6550 5075);
DISPLAY 0.638298 (-6550 5075);
FORCEPROP 1 LAST VALUE 100
J 2
(-6600 5075);
DISPLAY 0.638298 (-6600 5075);
FORCEPROP 1 LAST PACK_TYPE 0402LF
J 0
(-6950 4975);
DISPLAY 0.510638 (-6950 4975);
FORCEPROP 1 LAST WATTAGE 1/16W
J 2
(-6675 4975);
DISPLAY 0.510638 (-6675 4975);
FORCEPROP 1 LAST LOCATION R2593
J 0
(-7050 5075);
DISPLAY 0.510638 (-7050 5075);
FORCEPROP 1 LASTPIN (-6900 5075) $PN 1
J 0
(-6888 5087);
DISPLAY 0.787234 (-6888 5087);
PAINT MONO (-6888 5087);
FORCEPROP 1 LASTPIN (-6700 5075) $PN 2
J 0
(-6738 5087);
DISPLAY 0.787234 (-6738 5087);
PAINT MONO (-6738 5087);
FORCEPROP 2 LAST CDS_LIB pure_quanta
J 0
(-6800 5075);
DISPLAY INVISIBLE (-6800 5075);
FORCEPROP 1 LAST PATH I29
J 0
(-6850 5225);
DISPLAY 0.978723 (-6850 5225);
PAINT WHITE (-6850 5225);
DISPLAY INVISIBLE (-6850 5225);
FORCEPROP 0 LAST $SEC 1
J 0
(-6475 5125);
DISPLAY 0.680851 (-6475 5125);
PAINT MONO (-6475 5125);
DISPLAY INVISIBLE (-6475 5125);
FORCEPROP 0 LAST CDS_SEC 1
J 0
(-6475 5125);
DISPLAY 1.021277 (-6475 5125);
DISPLAY INVISIBLE (-6475 5125);
FORCEADD OFFPAGE..1
(-6800 100);
FORCEPROP 2 LAST $XR0 251 
J 0
(-7052 100);
DISPLAY 0.638298 (-7052 100);
PAINT MONO (-7052 100);
FORCEPROP 1 LAST COMMENT_BODY TRUE
J 0
(-6675 0);
DISPLAY 0.872340 (-6675 0);
PAINT GREEN (-6675 0);
DISPLAY INVISIBLE (-6675 0);
FORCEPROP 1 LAST OFFPAGE TRUE
J 0
(-6475 -25);
DISPLAY 0.872340 (-6475 -25);
PAINT GREEN (-6475 -25);
DISPLAY INVISIBLE (-6475 -25);
FORCEPROP 2 LAST CDS_LIB standard
J 0
(-6800 100);
PAINT MONO (-6800 100);
DISPLAY INVISIBLE (-6800 100);
FORCEPROP 2 LAST PATH I3
J 0
(-7050 150);
DISPLAY 1.021277 (-7050 150);
DISPLAY INVISIBLE (-7050 150);
FORCEADD OFFPAGE..5
(-6375 4700);
FORCEPROP 2 LAST $XR0 45 
J 0
(-6599 4700);
DISPLAY 0.638298 (-6599 4700);
PAINT MONO (-6599 4700);
FORCEPROP 1 LAST COMMENT_BODY TRUE
J 0
(-6275 4625);
DISPLAY 0.872340 (-6275 4625);
PAINT GREEN (-6275 4625);
DISPLAY INVISIBLE (-6275 4625);
FORCEPROP 1 LAST OFFPAGE TRUE
J 0
(-6050 4575);
DISPLAY 0.872340 (-6050 4575);
PAINT GREEN (-6050 4575);
DISPLAY INVISIBLE (-6050 4575);
FORCEPROP 2 LAST CDS_LIB standard
J 0
(-6375 4700);
DISPLAY INVISIBLE (-6375 4700);
FORCEPROP 2 LAST PATH I30
J 0
(-6575 4750);
DISPLAY 1.021277 (-6575 4750);
DISPLAY INVISIBLE (-6575 4750);
FORCEADD OFFPAGE..6
(-6375 4850);
FORCEPROP 2 LAST $XR0 45 
J 0
(-6624 4850);
DISPLAY 0.638298 (-6624 4850);
PAINT MONO (-6624 4850);
FORCEPROP 1 LAST COMMENT_BODY TRUE
J 0
(-6275 4775);
DISPLAY 0.872340 (-6275 4775);
PAINT GREEN (-6275 4775);
DISPLAY INVISIBLE (-6275 4775);
FORCEPROP 1 LAST OFFPAGE TRUE
J 0
(-6050 4725);
DISPLAY 0.872340 (-6050 4725);
PAINT GREEN (-6050 4725);
DISPLAY INVISIBLE (-6050 4725);
FORCEPROP 2 LAST CDS_LIB standard
J 0
(-6375 4850);
DISPLAY INVISIBLE (-6375 4850);
FORCEPROP 2 LAST PATH I31
J 0
(-6600 4900);
DISPLAY 1.021277 (-6600 4900);
DISPLAY INVISIBLE (-6600 4900);
FORCEADD OFFPAGE..1
(-6375 5000);
FORCEPROP 2 LAST $XR0 45 
J 0
(-6596 5000);
DISPLAY 0.638298 (-6596 5000);
PAINT MONO (-6596 5000);
FORCEPROP 1 LAST COMMENT_BODY TRUE
J 0
(-6250 4900);
DISPLAY 0.872340 (-6250 4900);
PAINT GREEN (-6250 4900);
DISPLAY INVISIBLE (-6250 4900);
FORCEPROP 1 LAST OFFPAGE TRUE
J 0
(-6050 4875);
DISPLAY 0.872340 (-6050 4875);
PAINT GREEN (-6050 4875);
DISPLAY INVISIBLE (-6050 4875);
FORCEPROP 2 LAST CDS_LIB standard
J 0
(-6375 5000);
DISPLAY INVISIBLE (-6375 5000);
FORCEPROP 2 LAST PATH I32
J 0
(-6575 5050);
DISPLAY 1.021277 (-6575 5050);
DISPLAY INVISIBLE (-6575 5050);
FORCEADD Q_RES..1
(-6800 5175);
FORCEPROP 1 LAST PART_NUMBER CS04992FB07
J 0
(-6650 5200);
DISPLAY 0.489362 (-6650 5200);
PAINT BLUE (-6650 5200);
DISPLAY INVISIBLE (-6650 5200);
FORCEPROP 1 LAST VALUE 49.9
J 2
(-6600 5175);
DISPLAY 0.489362 (-6600 5175);
PAINT SKYBLUE (-6600 5175);
FORCEPROP 1 LAST TOLERANCE 1%
J 0
(-6575 5175);
DISPLAY 0.489362 (-6575 5175);
PAINT SKYBLUE (-6575 5175);
FORCEPROP 1 LAST MATERIAL CHIP
J 0
(-6525 5175);
DISPLAY 0.489362 (-6525 5175);
PAINT SKYBLUE (-6525 5175);
FORCEPROP 1 LAST WATTAGE 1/16W
J 2
(-6350 5225);
DISPLAY 0.489362 (-6350 5225);
PAINT SKYBLUE (-6350 5225);
FORCEPROP 1 LAST PACK_TYPE 0402LF
J 0
(-6650 5225);
DISPLAY 0.489362 (-6650 5225);
PAINT SKYBLUE (-6650 5225);
FORCEPROP 1 LAST LOCATION R1718
J 0
(-7025 5175);
DISPLAY 0.617021 (-7025 5175);
PAINT AQUA (-7025 5175);
FORCEPROP 1 LASTPIN (-6900 5175) $PN 1
J 0
(-6888 5187);
DISPLAY 0.617021 (-6888 5187);
FORCEPROP 1 LASTPIN (-6700 5175) $PN 2
J 0
(-6738 5187);
DISPLAY 0.617021 (-6738 5187);
FORCEPROP 2 LAST CDS_LIB pure_quanta
J 0
(-6800 5175);
PAINT MONO (-6800 5175);
DISPLAY INVISIBLE (-6800 5175);
FORCEPROP 1 LAST PATH I33
J 0
(-6850 5325);
DISPLAY 0.978723 (-6850 5325);
PAINT WHITE (-6850 5325);
DISPLAY INVISIBLE (-6850 5325);
FORCEPROP 2 LAST $SEC 1
J 0
(-6850 5375);
DISPLAY 0.680851 (-6850 5375);
PAINT MONO (-6850 5375);
DISPLAY INVISIBLE (-6850 5375);
FORCEPROP 2 LAST CDS_SEC 1
J 0
(-6850 5375);
DISPLAY 1.021277 (-6850 5375);
DISPLAY INVISIBLE (-6850 5375);
FORCEADD OFFPAGE..1
(-6375 5300);
FORCEPROP 2 LAST $XR1 219 
J 0
(-6747 5300);
DISPLAY 0.638298 (-6747 5300);
PAINT MONO (-6747 5300);
FORCEPROP 2 LAST $XR0 214 
J 0
(-6627 5300);
DISPLAY 0.638298 (-6627 5300);
PAINT MONO (-6627 5300);
FORCEPROP 1 LAST COMMENT_BODY TRUE
J 0
(-6250 5200);
DISPLAY 0.872340 (-6250 5200);
PAINT GREEN (-6250 5200);
DISPLAY INVISIBLE (-6250 5200);
FORCEPROP 1 LAST OFFPAGE TRUE
J 0
(-6050 5175);
DISPLAY 0.872340 (-6050 5175);
PAINT GREEN (-6050 5175);
DISPLAY INVISIBLE (-6050 5175);
FORCEPROP 2 LAST CDS_LIB standard
J 0
(-6375 5300);
DISPLAY INVISIBLE (-6375 5300);
FORCEPROP 2 LAST PATH I34
J 0
(-6625 5350);
DISPLAY 1.021277 (-6625 5350);
DISPLAY INVISIBLE (-6625 5350);
FORCEADD OFFPAGE..5
(-6375 5450);
FORCEPROP 2 LAST $XR1 254 
J 0
(-6750 5450);
DISPLAY 0.638298 (-6750 5450);
PAINT MONO (-6750 5450);
FORCEPROP 2 LAST $XR0 214 
J 0
(-6630 5450);
DISPLAY 0.638298 (-6630 5450);
PAINT MONO (-6630 5450);
FORCEPROP 1 LAST COMMENT_BODY TRUE
J 0
(-6275 5375);
DISPLAY 0.872340 (-6275 5375);
PAINT GREEN (-6275 5375);
DISPLAY INVISIBLE (-6275 5375);
FORCEPROP 1 LAST OFFPAGE TRUE
J 0
(-6050 5325);
DISPLAY 0.872340 (-6050 5325);
PAINT GREEN (-6050 5325);
DISPLAY INVISIBLE (-6050 5325);
FORCEPROP 2 LAST CDS_LIB standard
J 0
(-6375 5450);
DISPLAY INVISIBLE (-6375 5450);
FORCEPROP 2 LAST PATH I35
J 0
(-6625 5500);
DISPLAY 1.021277 (-6625 5500);
DISPLAY INVISIBLE (-6625 5500);
FORCEADD Q_RES..1
(-5950 3600);
FORCEPROP 1 LAST PART_NUMBER CS11002FB07
J 0
(-5825 3650);
DISPLAY 0.617021 (-5825 3650);
PAINT BLUE (-5825 3650);
DISPLAY INVISIBLE (-5825 3650);
FORCEPROP 1 LAST PACK_TYPE 0402LF
J 0
(-5650 3600);
DISPLAY 0.617021 (-5650 3600);
PAINT SKYBLUE (-5650 3600);
FORCEPROP 1 LAST WATTAGE 1/16W
J 2
(-5525 3700);
DISPLAY 0.617021 (-5525 3700);
PAINT SKYBLUE (-5525 3700);
FORCEPROP 1 LAST TOLERANCE 1%
J 0
(-5725 3600);
DISPLAY 0.617021 (-5725 3600);
PAINT SKYBLUE (-5725 3600);
FORCEPROP 1 LAST MATERIAL CHIP
J 0
(-5825 3700);
DISPLAY 0.617021 (-5825 3700);
PAINT SKYBLUE (-5825 3700);
FORCEPROP 1 LAST VALUE 100
J 2
(-5750 3600);
DISPLAY 0.617021 (-5750 3600);
PAINT SKYBLUE (-5750 3600);
FORCEPROP 1 LAST LOCATION PR559
J 0
(-6225 3600);
DISPLAY 0.617021 (-6225 3600);
PAINT AQUA (-6225 3600);
FORCEPROP 1 LASTPIN (-6050 3600) $PN 1
J 0
(-6038 3612);
DISPLAY 0.617021 (-6038 3612);
FORCEPROP 1 LASTPIN (-5850 3600) $PN 2
J 0
(-5888 3612);
DISPLAY 0.617021 (-5888 3612);
FORCEPROP 2 LAST CDS_LIB pure_quanta
J 0
(-5950 3600);
PAINT MONO (-5950 3600);
DISPLAY INVISIBLE (-5950 3600);
FORCEPROP 1 LAST PATH I36
J 0
(-6000 3750);
DISPLAY 0.978723 (-6000 3750);
PAINT WHITE (-6000 3750);
DISPLAY INVISIBLE (-6000 3750);
FORCEPROP 2 LAST $SEC 1
J 0
(-6000 3800);
DISPLAY 0.680851 (-6000 3800);
PAINT MONO (-6000 3800);
DISPLAY INVISIBLE (-6000 3800);
FORCEPROP 2 LAST CDS_SEC 1
J 0
(-6000 3800);
DISPLAY 1.021277 (-6000 3800);
DISPLAY INVISIBLE (-6000 3800);
FORCEADD VCC15..1
(-5450 3750);
FORCEPROP 3 LASTPIN (-5450 3700) SIG_NAME PVCCD_HV_CPU1\g
J 0
(-5440 3710);
DISPLAY 0.659574 (-5440 3710);
PAINT MONO (-5440 3710);
DISPLAY INVISIBLE (-5440 3710);
FORCEPROP 1 LAST HDL_POWER PVCCD_HV_CPU1
J 1
(-5450 3800);
DISPLAY 0.617021 (-5450 3800);
PAINT GREEN (-5450 3800);
FORCEPROP 2 LAST CDS_LIB logical_power
J 0
(-5450 3750);
DISPLAY INVISIBLE (-5450 3750);
FORCEPROP 1 LAST PATH I37
J 0
(-5400 3775);
DISPLAY 0.872340 (-5400 3775);
PAINT AQUA (-5400 3775);
DISPLAY INVISIBLE (-5400 3775);
FORCEADD Q_RES..1
(-5325 4150);
FORCEPROP 1 LAST PART_NUMBER CS00002JB13
J 0
(-5425 4200);
DISPLAY 0.319149 (-5425 4200);
DISPLAY INVISIBLE (-5425 4200);
FORCEPROP 1 LAST VALUE 0
J 2
(-5150 4150);
DISPLAY 0.638298 (-5150 4150);
FORCEPROP 1 LAST MATERIAL CHIP
J 0
(-5050 4150);
DISPLAY 0.638298 (-5050 4150);
FORCEPROP 1 LAST TOLERANCE 5%
J 0
(-5125 4150);
DISPLAY 0.638298 (-5125 4150);
FORCEPROP 1 LAST WATTAGE 1/16W
J 2
(-5250 4225);
DISPLAY 0.319149 (-5250 4225);
FORCEPROP 1 LAST PACK_TYPE 0402LF
J 0
(-5425 4225);
DISPLAY 0.319149 (-5425 4225);
FORCEPROP 1 LAST LOCATION R2582
J 0
(-5675 4150);
DISPLAY 0.638298 (-5675 4150);
FORCEPROP 1 LASTPIN (-5425 4150) $PN 1
J 0
(-5413 4162);
DISPLAY 0.787234 (-5413 4162);
PAINT MONO (-5413 4162);
FORCEPROP 1 LASTPIN (-5225 4150) $PN 2
J 0
(-5263 4162);
DISPLAY 0.787234 (-5263 4162);
PAINT MONO (-5263 4162);
FORCEPROP 2 LAST CDS_LIB pure_quanta
J 0
(-5325 4150);
DISPLAY INVISIBLE (-5325 4150);
FORCEPROP 2 LAST SEC_TYPE 0402LF
J 0
(-5375 4350);
DISPLAY 1.021277 (-5375 4350);
DISPLAY INVISIBLE (-5375 4350);
FORCEPROP 1 LAST PATH I38
J 0
(-5375 4300);
DISPLAY 0.978723 (-5375 4300);
PAINT WHITE (-5375 4300);
DISPLAY INVISIBLE (-5375 4300);
FORCEPROP 2 LAST SEC 1
J 0
(-5375 4350);
DISPLAY 0.680851 (-5375 4350);
PAINT MONO (-5375 4350);
DISPLAY INVISIBLE (-5375 4350);
FORCEADD Q_RES..1
(-5325 4300);
FORCEPROP 1 LAST PART_NUMBER CS00002JB13
J 0
(-5200 4350);
DISPLAY 0.617021 (-5200 4350);
PAINT BLUE (-5200 4350);
DISPLAY INVISIBLE (-5200 4350);
FORCEPROP 1 LAST TOLERANCE 5%
J 0
(-5150 4300);
DISPLAY 0.617021 (-5150 4300);
PAINT SKYBLUE (-5150 4300);
FORCEPROP 1 LAST MATERIAL CHIP
J 0
(-5200 4400);
DISPLAY 0.617021 (-5200 4400);
PAINT SKYBLUE (-5200 4400);
FORCEPROP 1 LAST VALUE 0
J 2
(-5175 4300);
DISPLAY 0.617021 (-5175 4300);
PAINT SKYBLUE (-5175 4300);
FORCEPROP 1 LAST PACK_TYPE 0402LF
J 0
(-5075 4300);
DISPLAY 0.617021 (-5075 4300);
PAINT SKYBLUE (-5075 4300);
FORCEPROP 1 LAST WATTAGE 1/16W
J 2
(-4900 4400);
DISPLAY 0.617021 (-4900 4400);
PAINT SKYBLUE (-4900 4400);
FORCEPROP 1 LAST LOCATION R4595
J 0
(-5575 4300);
DISPLAY 0.617021 (-5575 4300);
PAINT AQUA (-5575 4300);
FORCEPROP 1 LASTPIN (-5425 4300) $PN 1
J 0
(-5413 4312);
DISPLAY 0.617021 (-5413 4312);
PAINT MONO (-5413 4312);
FORCEPROP 1 LASTPIN (-5225 4300) $PN 2
J 0
(-5263 4312);
DISPLAY 0.617021 (-5263 4312);
PAINT MONO (-5263 4312);
FORCEPROP 2 LAST CDS_LIB pure_quanta
J 0
(-5325 4300);
DISPLAY INVISIBLE (-5325 4300);
FORCEPROP 1 LAST PATH I39
J 0
(-5375 4450);
DISPLAY 0.978723 (-5375 4450);
PAINT WHITE (-5375 4450);
DISPLAY INVISIBLE (-5375 4450);
FORCEPROP 1 LAST LOCATION R4595
J 0
(-5375 4400);
DISPLAY 1.021277 (-5375 4400);
PAINT AQUA (-5375 4400);
DISPLAY INVISIBLE (-5375 4400);
FORCEPROP 0 LAST $SEC 1
J 0
(-5375 4400);
DISPLAY 0.680851 (-5375 4400);
PAINT MONO (-5375 4400);
DISPLAY INVISIBLE (-5375 4400);
FORCEPROP 0 LAST CDS_SEC 1
J 0
(-5375 4400);
DISPLAY 1.021277 (-5375 4400);
DISPLAY INVISIBLE (-5375 4400);
FORCEADD UNIVERSAL_GND..1
(-6850 150);
FORCEPROP 3 LASTPIN (-6850 200) SIG_NAME GND\g
J 0
(-6840 210);
DISPLAY 0.659574 (-6840 210);
PAINT MONO (-6840 210);
DISPLAY INVISIBLE (-6840 210);
FORCEPROP 1 LAST HDL_POWER GND
J 1
(-6825 75);
DISPLAY 0.872340 (-6825 75);
PAINT GREEN (-6825 75);
DISPLAY INVISIBLE (-6825 75);
FORCEPROP 2 LAST CDS_LIB logical_power
J 0
(-6850 150);
PAINT MONO (-6850 150);
DISPLAY INVISIBLE (-6850 150);
FORCEPROP 1 LAST PATH I4
J 0
(-6775 150);
DISPLAY 0.872340 (-6775 150);
PAINT AQUA (-6775 150);
DISPLAY INVISIBLE (-6775 150);
FORCEADD Q_RES..1
(-5325 4700);
FORCEPROP 1 LAST PART_NUMBER CS00002JB13
J 0
(-5200 4750);
DISPLAY 0.617021 (-5200 4750);
PAINT BLUE (-5200 4750);
DISPLAY INVISIBLE (-5200 4750);
FORCEPROP 1 LAST MATERIAL CHIP
J 0
(-5200 4800);
DISPLAY 0.617021 (-5200 4800);
PAINT SKYBLUE (-5200 4800);
FORCEPROP 1 LAST VALUE 0
J 2
(-5175 4700);
DISPLAY 0.617021 (-5175 4700);
PAINT SKYBLUE (-5175 4700);
FORCEPROP 1 LAST WATTAGE 1/16W
J 2
(-4900 4800);
DISPLAY 0.617021 (-4900 4800);
PAINT SKYBLUE (-4900 4800);
FORCEPROP 1 LAST TOLERANCE 5%
J 0
(-5150 4700);
DISPLAY 0.617021 (-5150 4700);
PAINT SKYBLUE (-5150 4700);
FORCEPROP 1 LAST PACK_TYPE 0402LF
J 0
(-5075 4700);
DISPLAY 0.617021 (-5075 4700);
PAINT SKYBLUE (-5075 4700);
FORCEPROP 1 LAST LOCATION R2580
J 0
(-5575 4700);
DISPLAY 0.617021 (-5575 4700);
PAINT AQUA (-5575 4700);
FORCEPROP 1 LASTPIN (-5425 4700) $PN 1
J 0
(-5413 4712);
DISPLAY 0.617021 (-5413 4712);
PAINT MONO (-5413 4712);
FORCEPROP 1 LASTPIN (-5225 4700) $PN 2
J 0
(-5263 4712);
DISPLAY 0.617021 (-5263 4712);
PAINT MONO (-5263 4712);
FORCEPROP 2 LAST CDS_LIB pure_quanta
J 0
(-5325 4700);
DISPLAY INVISIBLE (-5325 4700);
FORCEPROP 1 LAST PATH I40
J 0
(-5375 4850);
DISPLAY 0.978723 (-5375 4850);
PAINT WHITE (-5375 4850);
DISPLAY INVISIBLE (-5375 4850);
FORCEPROP 1 LAST LOCATION R2580
J 0
(-5375 4800);
DISPLAY 1.021277 (-5375 4800);
PAINT AQUA (-5375 4800);
DISPLAY INVISIBLE (-5375 4800);
FORCEPROP 0 LAST $SEC 1
J 0
(-5375 4800);
DISPLAY 0.680851 (-5375 4800);
PAINT MONO (-5375 4800);
DISPLAY INVISIBLE (-5375 4800);
FORCEPROP 0 LAST CDS_SEC 1
J 0
(-5375 4800);
DISPLAY 1.021277 (-5375 4800);
DISPLAY INVISIBLE (-5375 4800);
FORCEADD Q_RES..1
(-5325 4850);
FORCEPROP 1 LAST PART_NUMBER CS00002JB13
J 0
(-5200 4900);
DISPLAY 0.617021 (-5200 4900);
PAINT BLUE (-5200 4900);
DISPLAY INVISIBLE (-5200 4900);
FORCEPROP 1 LAST PACK_TYPE 0402LF
J 0
(-5075 4850);
DISPLAY 0.617021 (-5075 4850);
PAINT SKYBLUE (-5075 4850);
FORCEPROP 1 LAST TOLERANCE 5%
J 0
(-5150 4850);
DISPLAY 0.617021 (-5150 4850);
PAINT SKYBLUE (-5150 4850);
FORCEPROP 1 LAST VALUE 0
J 2
(-5175 4850);
DISPLAY 0.617021 (-5175 4850);
PAINT SKYBLUE (-5175 4850);
FORCEPROP 1 LAST WATTAGE 1/16W
J 2
(-4900 4950);
DISPLAY 0.617021 (-4900 4950);
PAINT SKYBLUE (-4900 4950);
FORCEPROP 1 LAST MATERIAL CHIP
J 0
(-5200 4950);
DISPLAY 0.617021 (-5200 4950);
PAINT SKYBLUE (-5200 4950);
FORCEPROP 1 LAST LOCATION R2579
J 0
(-5575 4850);
DISPLAY 0.617021 (-5575 4850);
PAINT AQUA (-5575 4850);
FORCEPROP 1 LASTPIN (-5425 4850) $PN 1
J 0
(-5413 4862);
DISPLAY 0.617021 (-5413 4862);
PAINT MONO (-5413 4862);
FORCEPROP 1 LASTPIN (-5225 4850) $PN 2
J 0
(-5263 4862);
DISPLAY 0.617021 (-5263 4862);
PAINT MONO (-5263 4862);
FORCEPROP 2 LAST CDS_LIB pure_quanta
J 0
(-5325 4850);
DISPLAY INVISIBLE (-5325 4850);
FORCEPROP 1 LAST PATH I41
J 0
(-5375 5000);
DISPLAY 0.978723 (-5375 5000);
PAINT WHITE (-5375 5000);
DISPLAY INVISIBLE (-5375 5000);
FORCEPROP 1 LAST LOCATION R2579
J 0
(-5375 4950);
DISPLAY 1.021277 (-5375 4950);
PAINT AQUA (-5375 4950);
DISPLAY INVISIBLE (-5375 4950);
FORCEPROP 0 LAST $SEC 1
J 0
(-5375 4950);
DISPLAY 0.680851 (-5375 4950);
PAINT MONO (-5375 4950);
DISPLAY INVISIBLE (-5375 4950);
FORCEPROP 0 LAST CDS_SEC 1
J 0
(-5375 4950);
DISPLAY 1.021277 (-5375 4950);
DISPLAY INVISIBLE (-5375 4950);
FORCEADD Q_RES..1
(-5325 5000);
FORCEPROP 1 LAST PART_NUMBER CS11502FB07
J 0
(-5200 5050);
DISPLAY 0.617021 (-5200 5050);
PAINT BLUE (-5200 5050);
DISPLAY INVISIBLE (-5200 5050);
FORCEPROP 1 LAST MATERIAL CHIP
J 0
(-5200 5100);
DISPLAY 0.617021 (-5200 5100);
PAINT SKYBLUE (-5200 5100);
FORCEPROP 1 LAST WATTAGE 1/16W
J 2
(-4900 5100);
DISPLAY 0.617021 (-4900 5100);
PAINT SKYBLUE (-4900 5100);
FORCEPROP 1 LAST VALUE 150
J 2
(-5100 5000);
DISPLAY 0.617021 (-5100 5000);
PAINT SKYBLUE (-5100 5000);
FORCEPROP 1 LAST TOLERANCE 1%
J 0
(-5075 5000);
DISPLAY 0.617021 (-5075 5000);
PAINT SKYBLUE (-5075 5000);
FORCEPROP 1 LAST PACK_TYPE 0402LF
J 0
(-4975 5000);
DISPLAY 0.617021 (-4975 5000);
PAINT SKYBLUE (-4975 5000);
FORCEPROP 1 LAST LOCATION R2578
J 0
(-5575 5000);
DISPLAY 0.617021 (-5575 5000);
PAINT AQUA (-5575 5000);
FORCEPROP 1 LASTPIN (-5425 5000) $PN 1
J 0
(-5413 5012);
DISPLAY 0.617021 (-5413 5012);
PAINT MONO (-5413 5012);
FORCEPROP 1 LASTPIN (-5225 5000) $PN 2
J 0
(-5263 5012);
DISPLAY 0.617021 (-5263 5012);
PAINT MONO (-5263 5012);
FORCEPROP 2 LAST CDS_LIB pure_quanta
J 0
(-5325 5000);
DISPLAY INVISIBLE (-5325 5000);
FORCEPROP 1 LAST PATH I42
J 0
(-5375 5150);
DISPLAY 0.978723 (-5375 5150);
PAINT WHITE (-5375 5150);
DISPLAY INVISIBLE (-5375 5150);
FORCEPROP 1 LAST LOCATION R2578
J 0
(-5175 5075);
DISPLAY 1.021277 (-5175 5075);
PAINT AQUA (-5175 5075);
DISPLAY INVISIBLE (-5175 5075);
FORCEPROP 0 LAST $SEC 1
J 0
(-5175 5075);
DISPLAY 0.680851 (-5175 5075);
PAINT MONO (-5175 5075);
DISPLAY INVISIBLE (-5175 5075);
FORCEPROP 0 LAST CDS_SEC 1
J 0
(-5175 5075);
DISPLAY 1.021277 (-5175 5075);
DISPLAY INVISIBLE (-5175 5075);
FORCEADD Q_RES..1
(-5325 5300);
FORCEPROP 1 LAST PART_NUMBER CS00002JB13
J 0
(-5200 5350);
DISPLAY 0.617021 (-5200 5350);
PAINT BLUE (-5200 5350);
DISPLAY INVISIBLE (-5200 5350);
FORCEPROP 1 LAST MATERIAL CHIP
J 0
(-5200 5400);
DISPLAY 0.617021 (-5200 5400);
PAINT SKYBLUE (-5200 5400);
FORCEPROP 1 LAST WATTAGE 1/16W
J 2
(-4900 5400);
DISPLAY 0.617021 (-4900 5400);
PAINT SKYBLUE (-4900 5400);
FORCEPROP 1 LAST VALUE 0
J 2
(-5175 5300);
DISPLAY 0.617021 (-5175 5300);
PAINT SKYBLUE (-5175 5300);
FORCEPROP 1 LAST PACK_TYPE 0402LF
J 0
(-5075 5300);
DISPLAY 0.617021 (-5075 5300);
PAINT SKYBLUE (-5075 5300);
FORCEPROP 1 LAST TOLERANCE 5%
J 0
(-5150 5300);
DISPLAY 0.617021 (-5150 5300);
PAINT SKYBLUE (-5150 5300);
FORCEPROP 1 LAST LOCATION R2577
J 0
(-5575 5300);
DISPLAY 0.617021 (-5575 5300);
PAINT AQUA (-5575 5300);
FORCEPROP 1 LASTPIN (-5425 5300) $PN 1
J 0
(-5413 5312);
DISPLAY 0.617021 (-5413 5312);
PAINT MONO (-5413 5312);
FORCEPROP 1 LASTPIN (-5225 5300) $PN 2
J 0
(-5263 5312);
DISPLAY 0.617021 (-5263 5312);
PAINT MONO (-5263 5312);
FORCEPROP 2 LAST CDS_LIB pure_quanta
J 0
(-5325 5300);
DISPLAY INVISIBLE (-5325 5300);
FORCEPROP 1 LAST PATH I43
J 0
(-5375 5450);
DISPLAY 0.978723 (-5375 5450);
PAINT WHITE (-5375 5450);
DISPLAY INVISIBLE (-5375 5450);
FORCEPROP 1 LAST LOCATION R2577
J 0
(-5375 5400);
DISPLAY 1.021277 (-5375 5400);
PAINT AQUA (-5375 5400);
DISPLAY INVISIBLE (-5375 5400);
FORCEPROP 0 LAST $SEC 1
J 0
(-5375 5400);
DISPLAY 0.680851 (-5375 5400);
PAINT MONO (-5375 5400);
DISPLAY INVISIBLE (-5375 5400);
FORCEPROP 0 LAST CDS_SEC 1
J 0
(-5375 5400);
DISPLAY 1.021277 (-5375 5400);
DISPLAY INVISIBLE (-5375 5400);
FORCEADD Q_RES..1
(-5325 5450);
FORCEPROP 1 LAST PART_NUMBER CS00002JB13
J 0
(-5200 5500);
DISPLAY 0.617021 (-5200 5500);
PAINT BLUE (-5200 5500);
DISPLAY INVISIBLE (-5200 5500);
FORCEPROP 1 LAST MATERIAL CHIP
J 0
(-5200 5550);
DISPLAY 0.617021 (-5200 5550);
PAINT SKYBLUE (-5200 5550);
FORCEPROP 1 LAST TOLERANCE 5%
J 0
(-5150 5450);
DISPLAY 0.617021 (-5150 5450);
PAINT SKYBLUE (-5150 5450);
FORCEPROP 1 LAST VALUE 0
J 2
(-5175 5450);
DISPLAY 0.617021 (-5175 5450);
PAINT SKYBLUE (-5175 5450);
FORCEPROP 1 LAST PACK_TYPE 0402LF
J 0
(-5075 5450);
DISPLAY 0.617021 (-5075 5450);
PAINT SKYBLUE (-5075 5450);
FORCEPROP 1 LAST WATTAGE 1/16W
J 2
(-4900 5550);
DISPLAY 0.617021 (-4900 5550);
PAINT SKYBLUE (-4900 5550);
FORCEPROP 1 LAST LOCATION R2576
J 0
(-5575 5450);
DISPLAY 0.617021 (-5575 5450);
PAINT AQUA (-5575 5450);
FORCEPROP 1 LASTPIN (-5425 5450) $PN 1
J 0
(-5413 5462);
DISPLAY 0.617021 (-5413 5462);
PAINT MONO (-5413 5462);
FORCEPROP 1 LASTPIN (-5225 5450) $PN 2
J 0
(-5263 5462);
DISPLAY 0.617021 (-5263 5462);
PAINT MONO (-5263 5462);
FORCEPROP 2 LAST CDS_LIB pure_quanta
J 0
(-5325 5450);
DISPLAY INVISIBLE (-5325 5450);
FORCEPROP 1 LAST PATH I44
J 0
(-5375 5600);
DISPLAY 0.978723 (-5375 5600);
PAINT WHITE (-5375 5600);
DISPLAY INVISIBLE (-5375 5600);
FORCEPROP 1 LAST LOCATION R2576
J 0
(-5375 5550);
DISPLAY 1.021277 (-5375 5550);
PAINT AQUA (-5375 5550);
DISPLAY INVISIBLE (-5375 5550);
FORCEPROP 0 LAST $SEC 1
J 0
(-5375 5550);
DISPLAY 0.680851 (-5375 5550);
PAINT MONO (-5375 5550);
DISPLAY INVISIBLE (-5375 5550);
FORCEPROP 0 LAST CDS_SEC 1
J 0
(-5375 5550);
DISPLAY 1.021277 (-5375 5550);
DISPLAY INVISIBLE (-5375 5550);
FORCEADD Q_CAP..2
(-4475 5600);
FORCEPROP 1 LAST PART_NUMBER TMP_QCH21006JB10
J 1
(-4200 5550);
DISPLAY 0.617021 (-4200 5550);
PAINT BLUE (-4200 5550);
DISPLAY INVISIBLE (-4200 5550);
FORCEPROP 1 LAST PACK_TYPE 0402
J 1
(-3950 5500);
DISPLAY 0.617021 (-3950 5500);
PAINT SKYBLUE (-3950 5500);
FORCEPROP 1 LAST TOLERANCE 5%
J 2
(-3825 5550);
DISPLAY 0.617021 (-3825 5550);
PAINT SKYBLUE (-3825 5550);
FORCEPROP 1 LAST VOLTAGE 50V
J 0
(-4125 5600);
DISPLAY 0.617021 (-4125 5600);
PAINT SKYBLUE (-4125 5600);
FORCEPROP 1 LAST MATERIAL EMPTY
J 0
(-4000 5600);
DISPLAY 0.617021 (-4000 5600);
PAINT RED (-4000 5600);
FORCEPROP 1 LAST VALUE 1000PF
J 2
(-4150 5600);
DISPLAY 0.617021 (-4150 5600);
PAINT SKYBLUE (-4150 5600);
FORCEPROP 1 LAST LOCATION C2454
J 1
(-4675 5600);
DISPLAY 0.617021 (-4675 5600);
PAINT AQUA (-4675 5600);
FORCEPROP 1 LASTPIN (-4575 5600) $PN 1
J 0
(-4585 5615);
DISPLAY 0.617021 (-4585 5615);
PAINT MONO (-4585 5615);
FORCEPROP 1 LASTPIN (-4375 5600) $PN 2
J 0
(-4390 5615);
DISPLAY 0.617021 (-4390 5615);
PAINT MONO (-4390 5615);
FORCEPROP 2 LAST CDS_LIB pure_quanta
J 0
(-4475 5600);
DISPLAY INVISIBLE (-4475 5600);
FORCEPROP 1 LAST PATH I45
J 0
(-4475 5800);
DISPLAY 0.978723 (-4475 5800);
PAINT WHITE (-4475 5800);
DISPLAY INVISIBLE (-4475 5800);
FORCEPROP 1 LAST LOCATION C2454
J 0
(-4525 5700);
DISPLAY 1.021277 (-4525 5700);
PAINT AQUA (-4525 5700);
DISPLAY INVISIBLE (-4525 5700);
FORCEPROP 0 LAST $SEC 1
J 0
(-4525 5700);
DISPLAY 0.680851 (-4525 5700);
PAINT MONO (-4525 5700);
DISPLAY INVISIBLE (-4525 5700);
FORCEPROP 0 LAST CDS_SEC 1
J 0
(-4525 5700);
DISPLAY 1.021277 (-4525 5700);
DISPLAY INVISIBLE (-4525 5700);
FORCEADD Q_RES..1
(-5325 5600);
FORCEPROP 1 LAST PART_NUMBER CS21002FB06
J 0
(-5200 5650);
DISPLAY 0.617021 (-5200 5650);
PAINT BLUE (-5200 5650);
DISPLAY INVISIBLE (-5200 5650);
FORCEPROP 1 LAST MATERIAL CHIP
J 0
(-5200 5700);
DISPLAY 0.617021 (-5200 5700);
PAINT SKYBLUE (-5200 5700);
FORCEPROP 1 LAST TOLERANCE 1%
J 0
(-5125 5600);
DISPLAY 0.617021 (-5125 5600);
PAINT SKYBLUE (-5125 5600);
FORCEPROP 1 LAST VALUE 1K
J 2
(-5150 5600);
DISPLAY 0.617021 (-5150 5600);
PAINT SKYBLUE (-5150 5600);
FORCEPROP 1 LAST PACK_TYPE 0402LF
J 0
(-5025 5600);
DISPLAY 0.617021 (-5025 5600);
PAINT SKYBLUE (-5025 5600);
FORCEPROP 1 LAST WATTAGE 1/16W
J 2
(-4900 5700);
DISPLAY 0.617021 (-4900 5700);
PAINT SKYBLUE (-4900 5700);
FORCEPROP 1 LAST LOCATION R2575
J 0
(-5575 5600);
DISPLAY 0.617021 (-5575 5600);
PAINT AQUA (-5575 5600);
FORCEPROP 1 LASTPIN (-5425 5600) $PN 1
J 0
(-5413 5612);
DISPLAY 0.617021 (-5413 5612);
PAINT MONO (-5413 5612);
FORCEPROP 1 LASTPIN (-5225 5600) $PN 2
J 0
(-5263 5612);
DISPLAY 0.617021 (-5263 5612);
PAINT MONO (-5263 5612);
FORCEPROP 2 LAST CDS_LIB pure_quanta
J 0
(-5325 5600);
DISPLAY INVISIBLE (-5325 5600);
FORCEPROP 1 LAST PATH I46
J 0
(-5375 5750);
DISPLAY 0.978723 (-5375 5750);
PAINT WHITE (-5375 5750);
DISPLAY INVISIBLE (-5375 5750);
FORCEPROP 1 LAST LOCATION R2575
J 0
(-5375 5700);
DISPLAY 1.021277 (-5375 5700);
PAINT AQUA (-5375 5700);
DISPLAY INVISIBLE (-5375 5700);
FORCEPROP 0 LAST $SEC 1
J 0
(-5375 5700);
DISPLAY 0.680851 (-5375 5700);
PAINT MONO (-5375 5700);
DISPLAY INVISIBLE (-5375 5700);
FORCEPROP 0 LAST CDS_SEC 1
J 0
(-5375 5700);
DISPLAY 1.021277 (-5375 5700);
DISPLAY INVISIBLE (-5375 5700);
FORCEADD VCC15..1
(-5750 5700);
FORCEPROP 3 LASTPIN (-5750 5650) SIG_NAME P3V3_AUX\g
J 0
(-5740 5660);
DISPLAY 0.659574 (-5740 5660);
PAINT MONO (-5740 5660);
DISPLAY INVISIBLE (-5740 5660);
FORCEPROP 1 LAST HDL_POWER P3V3_AUX
J 1
(-5750 5750);
DISPLAY 0.617021 (-5750 5750);
PAINT GREEN (-5750 5750);
FORCEPROP 2 LAST CDS_LIB logical_power
J 0
(-5750 5700);
PAINT MONO (-5750 5700);
DISPLAY INVISIBLE (-5750 5700);
FORCEPROP 1 LAST PATH I47
J 0
(-5700 5725);
DISPLAY 0.872340 (-5700 5725);
PAINT AQUA (-5700 5725);
DISPLAY INVISIBLE (-5700 5725);
FORCEADD Q_RES..2
R 2
(-4150 -200);
FORCEPROP 1 LAST PART_NUMBER CS21002FB06
J 2
(-4190 -325);
DISPLAY 0.617021 (-4190 -325);
PAINT BLUE (-4190 -325);
DISPLAY INVISIBLE (-4190 -325);
FORCEPROP 1 LAST VALUE 1K
J 2
(-4195 -125);
DISPLAY 0.617021 (-4195 -125);
PAINT SKYBLUE (-4195 -125);
FORCEPROP 1 LAST WATTAGE 1/16W
J 2
(-4190 -225);
DISPLAY 0.617021 (-4190 -225);
PAINT SKYBLUE (-4190 -225);
FORCEPROP 1 LAST MATERIAL EMPTY
J 2
(-4190 -275);
DISPLAY 0.617021 (-4190 -275);
PAINT RED (-4190 -275);
FORCEPROP 1 LAST TOLERANCE 1%
J 2
(-4195 -175);
DISPLAY 0.617021 (-4195 -175);
PAINT SKYBLUE (-4195 -175);
FORCEPROP 1 LAST PACK_TYPE 0402LF
J 2
(-4190 -375);
DISPLAY 0.617021 (-4190 -375);
PAINT SKYBLUE (-4190 -375);
FORCEPROP 1 LAST LOCATION PR218
J 2
(-4195 -75);
DISPLAY 0.617021 (-4195 -75);
PAINT AQUA (-4195 -75);
FORCEPROP 1 LASTPIN (-4150 -100) $PN 1
J 2
(-4155 -138);
DISPLAY 0.617021 (-4155 -138);
PAINT MONO (-4155 -138);
FORCEPROP 1 LASTPIN (-4150 -300) $PN 2
J 2
(-4155 -290);
DISPLAY 0.617021 (-4155 -290);
PAINT MONO (-4155 -290);
FORCEPROP 2 LAST CDS_LIB pure_quanta
J 2
(-4150 -200);
DISPLAY INVISIBLE (-4150 -200);
FORCEPROP 1 LAST PATH I48
J 2
(-4200 -25);
DISPLAY 0.978723 (-4200 -25);
PAINT WHITE (-4200 -25);
DISPLAY INVISIBLE (-4200 -25);
FORCEPROP 1 LAST LOCATION PR218
J 2
(-4200 -25);
DISPLAY 1.021277 (-4200 -25);
PAINT AQUA (-4200 -25);
DISPLAY INVISIBLE (-4200 -25);
FORCEPROP 0 LAST $SEC 1
J 2
(-4200 -25);
DISPLAY 0.680851 (-4200 -25);
PAINT MONO (-4200 -25);
DISPLAY INVISIBLE (-4200 -25);
FORCEPROP 0 LAST CDS_SEC 1
J 2
(-4200 -25);
DISPLAY 1.021277 (-4200 -25);
DISPLAY INVISIBLE (-4200 -25);
FORCEADD UNIVERSAL_GND..1
(-4025 -500);
FORCEPROP 3 LASTPIN (-4025 -450) SIG_NAME GND\g
J 0
(-4015 -440);
DISPLAY 0.659574 (-4015 -440);
PAINT MONO (-4015 -440);
DISPLAY INVISIBLE (-4015 -440);
FORCEPROP 1 LAST HDL_POWER GND
J 1
(-4000 -575);
DISPLAY 0.872340 (-4000 -575);
PAINT GREEN (-4000 -575);
DISPLAY INVISIBLE (-4000 -575);
FORCEPROP 2 LAST CDS_LIB logical_power
J 0
(-4025 -500);
PAINT MONO (-4025 -500);
DISPLAY INVISIBLE (-4025 -500);
FORCEPROP 1 LAST PATH I49
J 0
(-3950 -500);
DISPLAY 0.872340 (-3950 -500);
PAINT AQUA (-3950 -500);
DISPLAY INVISIBLE (-3950 -500);
FORCEADD OFFPAGE..1
(-7200 3450);
FORCEPROP 2 LAST $XR0 47 
J 0
(-7511 3450);
DISPLAY 0.638298 (-7511 3450);
PAINT MONO (-7511 3450);
FORCEPROP 1 LAST COMMENT_BODY TRUE
J 0
(-7075 3350);
DISPLAY 0.872340 (-7075 3350);
PAINT GREEN (-7075 3350);
DISPLAY INVISIBLE (-7075 3350);
FORCEPROP 1 LAST OFFPAGE TRUE
J 0
(-6875 3325);
DISPLAY 0.872340 (-6875 3325);
PAINT GREEN (-6875 3325);
DISPLAY INVISIBLE (-6875 3325);
FORCEPROP 2 LAST CDS_LIB standard
J 0
(-7200 3450);
DISPLAY INVISIBLE (-7200 3450);
FORCEPROP 2 LAST PATH I5
J 0
(-7500 3500);
DISPLAY 1.021277 (-7500 3500);
DISPLAY INVISIBLE (-7500 3500);
FORCEADD Q_CAP..1
(-4025 -200);
FORCEPROP 1 LAST PART_NUMBER CH4104K1B00
J 0
(-3975 -375);
DISPLAY 0.617021 (-3975 -375);
PAINT BLUE (-3975 -375);
DISPLAY INVISIBLE (-3975 -375);
FORCEPROP 1 LAST MATERIAL X7R
J 0
(-3975 -275);
DISPLAY 0.617021 (-3975 -275);
PAINT SKYBLUE (-3975 -275);
FORCEPROP 1 LAST TOLERANCE 10%
J 0
(-3975 -225);
DISPLAY 0.617021 (-3975 -225);
PAINT SKYBLUE (-3975 -225);
FORCEPROP 1 LAST VALUE 0.1UF
J 0
(-3975 -125);
DISPLAY 0.617021 (-3975 -125);
PAINT SKYBLUE (-3975 -125);
FORCEPROP 1 LAST VOLTAGE 25V
J 0
(-3975 -175);
DISPLAY 0.617021 (-3975 -175);
PAINT SKYBLUE (-3975 -175);
FORCEPROP 1 LAST PACK_TYPE 0402
J 0
(-3975 -325);
DISPLAY 0.617021 (-3975 -325);
PAINT SKYBLUE (-3975 -325);
FORCEPROP 1 LAST LOCATION PC390
J 0
(-3975 -75);
DISPLAY 0.617021 (-3975 -75);
PAINT AQUA (-3975 -75);
FORCEPROP 1 LASTPIN (-4025 -100) $PN 1
J 0
(-4015 -120);
DISPLAY 0.617021 (-4015 -120);
PAINT MONO (-4015 -120);
FORCEPROP 1 LASTPIN (-4025 -300) $PN 2
J 0
(-4015 -320);
DISPLAY 0.617021 (-4015 -320);
PAINT MONO (-4015 -320);
FORCEPROP 2 LAST CDS_LIB pure_quanta
J 0
(-4025 -200);
DISPLAY INVISIBLE (-4025 -200);
FORCEPROP 1 LAST PATH I50
J 0
(-3975 -50);
DISPLAY 0.978723 (-3975 -50);
PAINT WHITE (-3975 -50);
DISPLAY INVISIBLE (-3975 -50);
FORCEPROP 1 LAST LOCATION PC390
J 0
(-3975 -25);
DISPLAY 1.021277 (-3975 -25);
PAINT AQUA (-3975 -25);
DISPLAY INVISIBLE (-3975 -25);
FORCEPROP 0 LAST $SEC 1
J 0
(-3975 -25);
DISPLAY 0.680851 (-3975 -25);
PAINT MONO (-3975 -25);
DISPLAY INVISIBLE (-3975 -25);
FORCEPROP 0 LAST CDS_SEC 1
J 0
(-3975 -25);
DISPLAY 1.021277 (-3975 -25);
DISPLAY INVISIBLE (-3975 -25);
FORCEADD Q_CAP..2
(-4125 50);
FORCEPROP 1 LAST PART_NUMBER CH5103KEB01
J 1
(-3900 0);
DISPLAY 0.617021 (-3900 0);
PAINT BLUE (-3900 0);
DISPLAY INVISIBLE (-3900 0);
FORCEPROP 1 LAST MATERIAL X6S
J 0
(-3925 75);
DISPLAY 0.617021 (-3925 75);
PAINT SKYBLUE (-3925 75);
FORCEPROP 1 LAST VOLTAGE 16V
J 0
(-4250 25);
DISPLAY 0.617021 (-4250 25);
PAINT SKYBLUE (-4250 25);
FORCEPROP 1 LAST VALUE 1UF
J 2
(-4275 25);
DISPLAY 0.617021 (-4275 25);
PAINT SKYBLUE (-4275 25);
FORCEPROP 1 LAST TOLERANCE 10%
J 2
(-3875 25);
DISPLAY 0.617021 (-3875 25);
PAINT SKYBLUE (-3875 25);
FORCEPROP 1 LAST PACK_TYPE C0402
J 1
(-3800 25);
DISPLAY 0.617021 (-3800 25);
PAINT SKYBLUE (-3800 25);
FORCEPROP 1 LAST LOCATION PC814
J 1
(-4250 75);
DISPLAY 0.617021 (-4250 75);
PAINT AQUA (-4250 75);
FORCEPROP 2 LAST CDS_LIB pure_quanta
J 0
(-4125 50);
DISPLAY INVISIBLE (-4125 50);
FORCEPROP 1 LAST PATH I51
J 0
(-4125 250);
DISPLAY 0.978723 (-4125 250);
PAINT WHITE (-4125 250);
DISPLAY INVISIBLE (-4125 250);
FORCEPROP 0 LAST $SEC 1
J 0
(-3950 100);
DISPLAY INVISIBLE (-3950 100);
FORCEPROP 0 LAST CDS_SEC 1
J 0
(-3950 100);
DISPLAY INVISIBLE (-3950 100);
FORCEPROP 1 LASTPIN (-4225 50) $PN 1
J 0
(-4235 65);
DISPLAY 0.787234 (-4235 65);
PAINT MONO (-4235 65);
DISPLAY INVISIBLE (-4235 65);
FORCEPROP 1 LASTPIN (-4025 50) $PN 2
J 0
(-4040 65);
DISPLAY 0.787234 (-4040 65);
PAINT MONO (-4040 65);
DISPLAY INVISIBLE (-4040 65);
FORCEADD UNIVERSAL_GND..1
(-3725 -225);
FORCEPROP 3 LASTPIN (-3725 -175) SIG_NAME GND\g
J 0
(-3715 -165);
DISPLAY 0.659574 (-3715 -165);
PAINT MONO (-3715 -165);
DISPLAY INVISIBLE (-3715 -165);
FORCEPROP 1 LAST HDL_POWER GND
J 1
(-3700 -300);
DISPLAY 0.872340 (-3700 -300);
PAINT GREEN (-3700 -300);
DISPLAY INVISIBLE (-3700 -300);
FORCEPROP 2 LAST CDS_LIB logical_power
J 0
(-3725 -225);
PAINT MONO (-3725 -225);
DISPLAY INVISIBLE (-3725 -225);
FORCEPROP 1 LAST PATH I52
J 0
(-3650 -225);
DISPLAY 0.872340 (-3650 -225);
PAINT AQUA (-3650 -225);
DISPLAY INVISIBLE (-3650 -225);
FORCEADD ISL69260IRAZT..1
(-2950 2700);
FORCEPROP 1 LAST PART_NUMBER AL069260000
J 0
(-3495 5645);
DISPLAY 0.617021 (-3495 5645);
PAINT BLUE (-3495 5645);
DISPLAY INVISIBLE (-3495 5645);
FORCEPROP 2 LAST VALUE ISL69260IRAZ-T
J 0
(-2950 5650);
DISPLAY 0.617021 (-2950 5650);
PAINT SKYBLUE (-2950 5650);
FORCEPROP 2 LAST PART_TYPE SMLF
J 0
(-2950 5700);
DISPLAY 0.638298 (-2950 5700);
FORCEPROP 1 LAST MATERIAL IC
J 0
(-3495 5558);
DISPLAY 0.617021 (-3495 5558);
PAINT SKYBLUE (-3495 5558);
FORCEPROP 1 LAST LOCATION PU18
J 0
(-3495 5752);
DISPLAY 0.617021 (-3495 5752);
PAINT AQUA (-3495 5752);
FORCEPROP 0 LASTPIN (-3625 350) $PN 34
J 2
(-3635 360);
DISPLAY 0.680851 (-3635 360);
PAINT MONO (-3635 360);
FORCEPROP 0 LASTPIN (-3625 1450) $PN 33
J 2
(-3635 1460);
DISPLAY 0.680851 (-3635 1460);
PAINT MONO (-3635 1460);
FORCEPROP 0 LASTPIN (-2275 1200) $PN 30
J 0
(-2265 1210);
DISPLAY 0.680851 (-2265 1210);
PAINT MONO (-2265 1210);
FORCEPROP 0 LASTPIN (-2275 1650) $PN 29
J 0
(-2265 1660);
DISPLAY 0.680851 (-2265 1660);
PAINT MONO (-2265 1660);
FORCEPROP 0 LASTPIN (-2275 2100) $PN 28
J 0
(-2265 2110);
DISPLAY 0.680851 (-2265 2110);
PAINT MONO (-2265 2110);
FORCEPROP 0 LASTPIN (-2275 2550) $PN 27
J 0
(-2265 2560);
DISPLAY 0.680851 (-2265 2560);
PAINT MONO (-2265 2560);
FORCEPROP 0 LASTPIN (-2275 3000) $PN 26
J 0
(-2265 3010);
DISPLAY 0.680851 (-2265 3010);
PAINT MONO (-2265 3010);
FORCEPROP 0 LASTPIN (-2275 3450) $PN 25
J 0
(-2265 3460);
DISPLAY 0.680851 (-2265 3460);
PAINT MONO (-2265 3460);
FORCEPROP 0 LASTPIN (-2275 3900) $PN 24
J 0
(-2265 3910);
DISPLAY 0.680851 (-2265 3910);
PAINT MONO (-2265 3910);
FORCEPROP 0 LASTPIN (-2275 4350) $PN 23
J 0
(-2265 4360);
DISPLAY 0.680851 (-2265 4360);
PAINT MONO (-2265 4360);
FORCEPROP 0 LASTPIN (-3625 5300) $PN 13
J 2
(-3635 5310);
DISPLAY 0.680851 (-3635 5310);
PAINT MONO (-3635 5310);
FORCEPROP 0 LASTPIN (-3625 1050) $PN 20
J 2
(-3635 1060);
DISPLAY 0.680851 (-3635 1060);
PAINT MONO (-3635 1060);
FORCEPROP 0 LASTPIN (-3625 5450) $PN 12
J 2
(-3635 5460);
DISPLAY 0.680851 (-3635 5460);
PAINT MONO (-3635 5460);
FORCEPROP 0 LASTPIN (-3625 650) $PN 16
J 2
(-3635 660);
DISPLAY 0.680851 (-3635 660);
PAINT MONO (-3635 660);
FORCEPROP 0 LASTPIN (-3625 4300) $PN 10
J 2
(-3635 4310);
DISPLAY 0.680851 (-3635 4310);
PAINT MONO (-3635 4310);
FORCEPROP 0 LASTPIN (-3625 4150) $PN 9
J 2
(-3635 4160);
DISPLAY 0.680851 (-3635 4160);
PAINT MONO (-3635 4160);
FORCEPROP 0 LASTPIN (-2275 1300) $PN 1
J 0
(-2265 1310);
DISPLAY 0.680851 (-2265 1310);
PAINT MONO (-2265 1310);
FORCEPROP 0 LASTPIN (-2275 1750) $PN 2
J 0
(-2265 1760);
DISPLAY 0.680851 (-2265 1760);
PAINT MONO (-2265 1760);
FORCEPROP 0 LASTPIN (-2275 2200) $PN 3
J 0
(-2265 2210);
DISPLAY 0.680851 (-2265 2210);
PAINT MONO (-2265 2210);
FORCEPROP 0 LASTPIN (-2275 2650) $PN 4
J 0
(-2265 2660);
DISPLAY 0.680851 (-2265 2660);
PAINT MONO (-2265 2660);
FORCEPROP 0 LASTPIN (-2275 3100) $PN 5
J 0
(-2265 3110);
DISPLAY 0.680851 (-2265 3110);
PAINT MONO (-2265 3110);
FORCEPROP 0 LASTPIN (-2275 3550) $PN 6
J 0
(-2265 3560);
DISPLAY 0.680851 (-2265 3560);
PAINT MONO (-2265 3560);
FORCEPROP 0 LASTPIN (-2275 4000) $PN 7
J 0
(-2265 4010);
DISPLAY 0.680851 (-2265 4010);
PAINT MONO (-2265 4010);
FORCEPROP 0 LASTPIN (-2275 4450) $PN 8
J 0
(-2265 4460);
DISPLAY 0.680851 (-2265 4460);
PAINT MONO (-2265 4460);
FORCEPROP 0 LASTPIN (-3625 3150) $PN 22
J 2
(-3635 3160);
DISPLAY 0.680851 (-3635 3160);
PAINT MONO (-3635 3160);
FORCEPROP 0 LASTPIN (-3625 2050) $PN 31
J 2
(-3635 2060);
DISPLAY 0.680851 (-3635 2060);
PAINT MONO (-3635 2060);
FORCEPROP 0 LASTPIN (-3625 5000) $PN 17
J 2
(-3635 5010);
DISPLAY 0.680851 (-3635 5010);
PAINT MONO (-3635 5010);
FORCEPROP 0 LASTPIN (-3625 4850) $PN 18
J 2
(-3635 4860);
DISPLAY 0.680851 (-3635 4860);
PAINT MONO (-3635 4860);
FORCEPROP 0 LASTPIN (-2275 250) $PN 35
J 0
(-2265 260);
DISPLAY 0.680851 (-2265 260);
PAINT MONO (-2265 260);
FORCEPROP 0 LASTPIN (-2275 550) $PN 36
J 0
(-2265 560);
DISPLAY 0.680851 (-2265 560);
PAINT MONO (-2265 560);
FORCEPROP 0 LASTPIN (-3625 -100) $PN TH
J 2
(-3635 -90);
DISPLAY 0.680851 (-3635 -90);
PAINT MONO (-3635 -90);
FORCEPROP 0 LASTPIN (-2275 5450) $PN 39
J 0
(-2265 5460);
DISPLAY 0.680851 (-2265 5460);
PAINT MONO (-2265 5460);
FORCEPROP 0 LASTPIN (-2275 5150) $PN 40
J 0
(-2265 5160);
DISPLAY 0.680851 (-2265 5160);
PAINT MONO (-2265 5160);
FORCEPROP 0 LASTPIN (-3625 3400) $PN 21
J 2
(-3635 3410);
DISPLAY 0.680851 (-3635 3410);
PAINT MONO (-3635 3410);
FORCEPROP 0 LASTPIN (-3625 2300) $PN 32
J 2
(-3635 2310);
DISPLAY 0.680851 (-3635 2310);
PAINT MONO (-3635 2310);
FORCEPROP 0 LASTPIN (-3625 1200) $PN 15
J 2
(-3635 1210);
DISPLAY 0.680851 (-3635 1210);
PAINT MONO (-3635 1210);
FORCEPROP 0 LASTPIN (-3625 4000) $PN 11
J 2
(-3635 4010);
DISPLAY 0.680851 (-3635 4010);
PAINT MONO (-3635 4010);
FORCEPROP 0 LASTPIN (-3625 4700) $PN 19
J 2
(-3635 4710);
DISPLAY 0.680851 (-3635 4710);
PAINT MONO (-3635 4710);
FORCEPROP 0 LASTPIN (-2275 950) $PN 14
J 0
(-2265 960);
DISPLAY 0.680851 (-2265 960);
PAINT MONO (-2265 960);
FORCEPROP 0 LASTPIN (-3625 0) $PN 38
J 2
(-3635 10);
DISPLAY 0.680851 (-3635 10);
PAINT MONO (-3635 10);
FORCEPROP 0 LASTPIN (-3625 100) $PN 37
J 2
(-3635 110);
DISPLAY 0.680851 (-3635 110);
PAINT MONO (-3635 110);
FORCEPROP 1 LAST PATH I53
J 0
(-2950 2700);
DISPLAY 0.723404 (-2950 2700);
PAINT GREEN (-2950 2700);
DISPLAY INVISIBLE (-2950 2700);
FORCEPROP 1 LAST NEEDS_NO_SIZE TRUE
J 0
(-2950 2700);
DISPLAY 0.723404 (-2950 2700);
PAINT GREEN (-2950 2700);
DISPLAY INVISIBLE (-2950 2700);
FORCEPROP 1 LAST CDS_LMAN_SYM_OUTLINE -550,2850,500,-2850
J 0
(-2950 2700);
DISPLAY 0.468085 (-2950 2700);
PAINT GREEN (-2950 2700);
DISPLAY INVISIBLE (-2950 2700);
FORCEPROP 2 LAST CDS_LIB pure_quanta
J 0
(-2950 2700);
DISPLAY INVISIBLE (-2950 2700);
FORCEPROP 0 LAST $SEC 1
J 0
(-3475 5800);
DISPLAY 0.680851 (-3475 5800);
PAINT MONO (-3475 5800);
DISPLAY INVISIBLE (-3475 5800);
FORCEPROP 0 LAST CDS_SEC 1
J 0
(-3450 5775);
DISPLAY 1.021277 (-3450 5775);
DISPLAY INVISIBLE (-3450 5775);
FORCEADD UNIVERSAL_GND..1
(-3775 925);
FORCEPROP 3 LASTPIN (-3775 975) SIG_NAME GND\g
J 0
(-3765 985);
DISPLAY 0.659574 (-3765 985);
PAINT MONO (-3765 985);
DISPLAY INVISIBLE (-3765 985);
FORCEPROP 1 LAST HDL_POWER GND
J 1
(-3750 850);
DISPLAY 0.872340 (-3750 850);
PAINT GREEN (-3750 850);
DISPLAY INVISIBLE (-3750 850);
FORCEPROP 2 LAST CDS_LIB logical_power
J 0
(-3775 925);
PAINT MONO (-3775 925);
DISPLAY INVISIBLE (-3775 925);
FORCEPROP 1 LAST PATH I54
J 0
(-3700 925);
DISPLAY 0.872340 (-3700 925);
PAINT AQUA (-3700 925);
DISPLAY INVISIBLE (-3700 925);
FORCEADD UNIVERSAL_GND..1
(-3825 1850);
FORCEPROP 3 LASTPIN (-3825 1900) SIG_NAME GND\g
J 0
(-3815 1910);
DISPLAY 0.659574 (-3815 1910);
PAINT MONO (-3815 1910);
DISPLAY INVISIBLE (-3815 1910);
FORCEPROP 1 LAST HDL_POWER GND
J 1
(-3800 1775);
DISPLAY 0.872340 (-3800 1775);
PAINT GREEN (-3800 1775);
DISPLAY INVISIBLE (-3800 1775);
FORCEPROP 2 LAST CDS_LIB logical_power
J 0
(-3825 1850);
PAINT MONO (-3825 1850);
DISPLAY INVISIBLE (-3825 1850);
FORCEPROP 1 LAST PATH I55
J 0
(-3750 1850);
DISPLAY 0.872340 (-3750 1850);
PAINT AQUA (-3750 1850);
DISPLAY INVISIBLE (-3750 1850);
FORCEADD UNIVERSAL_GND..1
(-1325 -175);
FORCEPROP 3 LASTPIN (-1325 -125) SIG_NAME GND\g
J 0
(-1315 -115);
DISPLAY 0.659574 (-1315 -115);
PAINT MONO (-1315 -115);
DISPLAY INVISIBLE (-1315 -115);
FORCEPROP 1 LAST HDL_POWER GND
J 1
(-1300 -250);
DISPLAY 0.872340 (-1300 -250);
PAINT GREEN (-1300 -250);
DISPLAY INVISIBLE (-1300 -250);
FORCEPROP 2 LAST CDS_LIB logical_power
J 0
(-1325 -175);
PAINT MONO (-1325 -175);
DISPLAY INVISIBLE (-1325 -175);
FORCEPROP 1 LAST PATH I56
J 0
(-1250 -175);
DISPLAY 0.872340 (-1250 -175);
PAINT AQUA (-1250 -175);
DISPLAY INVISIBLE (-1250 -175);
FORCEADD Q_CAP..1
(-1325 50);
FORCEPROP 1 LAST PART_NUMBER TMP_QCH14706KB18
J 0
(-1275 -150);
DISPLAY 0.617021 (-1275 -150);
PAINT BLUE (-1275 -150);
DISPLAY INVISIBLE (-1275 -150);
FORCEPROP 1 LAST MATERIAL X7R
J 0
(-1275 -50);
DISPLAY 0.617021 (-1275 -50);
PAINT SKYBLUE (-1275 -50);
FORCEPROP 1 LAST TOLERANCE 10%
J 0
(-1275 0);
DISPLAY 0.617021 (-1275 0);
PAINT SKYBLUE (-1275 0);
FORCEPROP 1 LAST VALUE 470PF
J 0
(-1275 100);
DISPLAY 0.617021 (-1275 100);
PAINT SKYBLUE (-1275 100);
FORCEPROP 1 LAST VOLTAGE 50V
J 0
(-1275 50);
DISPLAY 0.617021 (-1275 50);
PAINT SKYBLUE (-1275 50);
FORCEPROP 1 LAST PACK_TYPE 0402
J 0
(-1275 -100);
DISPLAY 0.617021 (-1275 -100);
PAINT SKYBLUE (-1275 -100);
FORCEPROP 1 LAST LOCATION PC393
J 0
(-1275 150);
DISPLAY 0.617021 (-1275 150);
PAINT AQUA (-1275 150);
FORCEPROP 1 LASTPIN (-1325 150) $PN 1
J 0
(-1315 130);
DISPLAY 0.617021 (-1315 130);
PAINT MONO (-1315 130);
FORCEPROP 1 LASTPIN (-1325 -50) $PN 2
J 0
(-1315 -70);
DISPLAY 0.617021 (-1315 -70);
PAINT MONO (-1315 -70);
FORCEPROP 2 LAST CDS_LIB pure_quanta
J 0
(-1325 50);
DISPLAY INVISIBLE (-1325 50);
FORCEPROP 1 LAST PATH I57
J 0
(-1275 200);
DISPLAY 0.978723 (-1275 200);
PAINT WHITE (-1275 200);
DISPLAY INVISIBLE (-1275 200);
FORCEPROP 1 LAST LOCATION PC393
J 0
(-1275 200);
DISPLAY 1.021277 (-1275 200);
PAINT AQUA (-1275 200);
DISPLAY INVISIBLE (-1275 200);
FORCEPROP 0 LAST $SEC 1
J 0
(-1275 200);
DISPLAY 0.680851 (-1275 200);
PAINT MONO (-1275 200);
DISPLAY INVISIBLE (-1275 200);
FORCEPROP 0 LAST CDS_SEC 1
J 0
(-1275 200);
DISPLAY 1.021277 (-1275 200);
DISPLAY INVISIBLE (-1275 200);
FORCEADD Q_RES..1
(-800 950);
FORCEPROP 1 LAST PART_NUMBER CS00002JB13
J 0
(-675 1000);
DISPLAY 0.638298 (-675 1000);
DISPLAY INVISIBLE (-675 1000);
FORCEPROP 1 LAST PACK_TYPE 0402LF
J 0
(-675 1025);
DISPLAY 0.638298 (-675 1025);
FORCEPROP 1 LAST WATTAGE 1/16W
J 2
(-225 950);
DISPLAY 0.638298 (-225 950);
FORCEPROP 1 LAST VALUE 0
J 2
(-625 950);
DISPLAY 0.638298 (-625 950);
FORCEPROP 1 LAST TOLERANCE 5%
J 0
(-600 950);
DISPLAY 0.638298 (-600 950);
FORCEPROP 1 LAST MATERIAL CHIP
J 0
(-525 950);
DISPLAY 0.638298 (-525 950);
FORCEPROP 1 LAST LOCATION R2557
J 0
(-1075 950);
DISPLAY 0.808511 (-1075 950);
FORCEPROP 1 LASTPIN (-900 950) $PN 1
J 0
(-888 962);
DISPLAY 0.787234 (-888 962);
PAINT MONO (-888 962);
FORCEPROP 1 LASTPIN (-700 950) $PN 2
J 0
(-738 962);
DISPLAY 0.787234 (-738 962);
PAINT MONO (-738 962);
FORCEPROP 2 LAST CDS_LIB pure_quanta
J 0
(-800 950);
DISPLAY INVISIBLE (-800 950);
FORCEPROP 2 LAST SEC_TYPE 0402LF
J 0
(-850 1150);
DISPLAY 1.021277 (-850 1150);
DISPLAY INVISIBLE (-850 1150);
FORCEPROP 1 LAST PATH I58
J 0
(-850 1100);
DISPLAY 0.978723 (-850 1100);
PAINT WHITE (-850 1100);
DISPLAY INVISIBLE (-850 1100);
FORCEPROP 2 LAST SEC 1
J 0
(-850 1150);
DISPLAY 0.680851 (-850 1150);
PAINT MONO (-850 1150);
DISPLAY INVISIBLE (-850 1150);
FORCEADD Q_RES..1
(-800 1200);
FORCEPROP 1 LAST PART_NUMBER CS00002JB13
J 0
(-675 1250);
DISPLAY 0.617021 (-675 1250);
PAINT BLUE (-675 1250);
DISPLAY INVISIBLE (-675 1250);
FORCEPROP 1 LAST MATERIAL CHIP
J 0
(-550 1200);
DISPLAY 0.617021 (-550 1200);
PAINT SKYBLUE (-550 1200);
FORCEPROP 1 LAST VALUE 0
J 2
(-650 1200);
DISPLAY 0.617021 (-650 1200);
PAINT SKYBLUE (-650 1200);
FORCEPROP 1 LAST TOLERANCE 5%
J 0
(-625 1200);
DISPLAY 0.617021 (-625 1200);
PAINT SKYBLUE (-625 1200);
FORCEPROP 1 LAST LOCATION PR4257
J 0
(-1075 1200);
DISPLAY 0.787234 (-1075 1200);
FORCEPROP 1 LASTPIN (-900 1200) $PN 1
J 0
(-888 1212);
DISPLAY 0.787234 (-888 1212);
PAINT MONO (-888 1212);
FORCEPROP 1 LASTPIN (-700 1200) $PN 2
J 0
(-738 1212);
DISPLAY 0.787234 (-738 1212);
PAINT MONO (-738 1212);
FORCEPROP 2 LAST CDS_LIB pure_quanta
J 0
(-800 1200);
DISPLAY INVISIBLE (-800 1200);
FORCEPROP 1 LAST PACK_TYPE 0402LF
J 0
(-850 1300);
DISPLAY 0.404255 (-850 1300);
PAINT SKYBLUE (-850 1300);
DISPLAY INVISIBLE (-850 1300);
FORCEPROP 1 LAST WATTAGE 1/16W
J 2
(-625 1275);
DISPLAY 0.404255 (-625 1275);
PAINT SKYBLUE (-625 1275);
DISPLAY INVISIBLE (-625 1275);
FORCEPROP 1 LAST PATH I59
J 0
(-850 1350);
DISPLAY 0.978723 (-850 1350);
PAINT WHITE (-850 1350);
DISPLAY INVISIBLE (-850 1350);
FORCEPROP 0 LAST $SEC 1
J 0
(-675 1300);
DISPLAY 0.680851 (-675 1300);
PAINT MONO (-675 1300);
DISPLAY INVISIBLE (-675 1300);
FORCEPROP 0 LAST CDS_SEC 1
J 0
(-675 1300);
DISPLAY 1.021277 (-675 1300);
DISPLAY INVISIBLE (-675 1300);
FORCEADD OFFPAGE..1
(-7200 3075);
FORCEPROP 2 LAST $XR0 47 
J 0
(-7511 3075);
DISPLAY 0.638298 (-7511 3075);
PAINT MONO (-7511 3075);
FORCEPROP 1 LAST COMMENT_BODY TRUE
J 0
(-7075 2975);
DISPLAY 0.872340 (-7075 2975);
PAINT GREEN (-7075 2975);
DISPLAY INVISIBLE (-7075 2975);
FORCEPROP 1 LAST OFFPAGE TRUE
J 0
(-6875 2950);
DISPLAY 0.872340 (-6875 2950);
PAINT GREEN (-6875 2950);
DISPLAY INVISIBLE (-6875 2950);
FORCEPROP 2 LAST CDS_LIB standard
J 0
(-7200 3075);
DISPLAY INVISIBLE (-7200 3075);
FORCEPROP 2 LAST PATH I6
J 0
(-7500 3125);
DISPLAY 1.021277 (-7500 3125);
DISPLAY INVISIBLE (-7500 3125);
FORCEADD Q_RES..1
(-475 550);
FORCEPROP 1 LAST PART_NUMBER CS00002JB13
J 0
(-600 600);
DISPLAY 0.617021 (-600 600);
PAINT BLUE (-600 600);
DISPLAY INVISIBLE (-600 600);
FORCEPROP 1 LAST PACK_TYPE 0402LF
J 0
(-600 650);
DISPLAY 0.617021 (-600 650);
PAINT SKYBLUE (-600 650);
FORCEPROP 1 LAST WATTAGE 1/16W
J 2
(-225 650);
DISPLAY 0.617021 (-225 650);
PAINT SKYBLUE (-225 650);
FORCEPROP 1 LAST MATERIAL CHIP
J 0
(-200 550);
DISPLAY 0.617021 (-200 550);
PAINT SKYBLUE (-200 550);
FORCEPROP 1 LAST TOLERANCE 5%
J 0
(-275 550);
DISPLAY 0.617021 (-275 550);
PAINT SKYBLUE (-275 550);
FORCEPROP 1 LAST VALUE 0
J 2
(-300 550);
DISPLAY 0.617021 (-300 550);
PAINT SKYBLUE (-300 550);
FORCEPROP 1 LAST LOCATION PR1315
J 0
(-750 550);
DISPLAY 0.617021 (-750 550);
PAINT AQUA (-750 550);
FORCEPROP 1 LASTPIN (-575 550) $PN 1
J 0
(-563 562);
DISPLAY 0.617021 (-563 562);
PAINT MONO (-563 562);
FORCEPROP 1 LASTPIN (-375 550) $PN 2
J 0
(-413 562);
DISPLAY 0.617021 (-413 562);
PAINT MONO (-413 562);
FORCEPROP 2 LAST CDS_LIB pure_quanta
J 0
(-475 550);
DISPLAY INVISIBLE (-475 550);
FORCEPROP 1 LAST PATH I60
J 0
(-525 700);
DISPLAY 0.978723 (-525 700);
PAINT WHITE (-525 700);
DISPLAY INVISIBLE (-525 700);
FORCEPROP 0 LAST $SEC 1
J 0
(-225 700);
DISPLAY 0.680851 (-225 700);
PAINT MONO (-225 700);
DISPLAY INVISIBLE (-225 700);
FORCEPROP 0 LAST CDS_SEC 1
J 0
(-225 700);
DISPLAY 1.021277 (-225 700);
DISPLAY INVISIBLE (-225 700);
FORCEADD Q_RES..1
(-475 800);
FORCEPROP 1 LAST PART_NUMBER CS00002JB13
J 0
(-600 850);
DISPLAY 0.617021 (-600 850);
PAINT BLUE (-600 850);
DISPLAY INVISIBLE (-600 850);
FORCEPROP 1 LAST PACK_TYPE 0402LF
J 0
(-600 900);
DISPLAY 0.617021 (-600 900);
PAINT SKYBLUE (-600 900);
FORCEPROP 1 LAST WATTAGE 1/16W
J 2
(-225 900);
DISPLAY 0.617021 (-225 900);
PAINT SKYBLUE (-225 900);
FORCEPROP 1 LAST MATERIAL EMPTY
J 0
(-200 800);
DISPLAY 0.617021 (-200 800);
PAINT RED (-200 800);
FORCEPROP 1 LAST VALUE 0
J 2
(-300 800);
DISPLAY 0.617021 (-300 800);
PAINT SKYBLUE (-300 800);
FORCEPROP 1 LAST TOLERANCE 5%
J 0
(-275 800);
DISPLAY 0.617021 (-275 800);
PAINT SKYBLUE (-275 800);
FORCEPROP 1 LAST LOCATION PR410
J 0
(-750 800);
DISPLAY 0.617021 (-750 800);
PAINT AQUA (-750 800);
FORCEPROP 2 LAST CDS_LIB pure_quanta
J 0
(-475 800);
DISPLAY INVISIBLE (-475 800);
FORCEPROP 1 LAST PATH I61
J 0
(-525 950);
DISPLAY 0.978723 (-525 950);
PAINT WHITE (-525 950);
DISPLAY INVISIBLE (-525 950);
FORCEPROP 0 LAST $SEC 1
J 0
(-225 950);
DISPLAY INVISIBLE (-225 950);
FORCEPROP 0 LAST CDS_SEC 1
J 0
(-225 950);
DISPLAY INVISIBLE (-225 950);
FORCEPROP 1 LASTPIN (-575 800) $PN 1
J 0
(-563 812);
DISPLAY 0.787234 (-563 812);
PAINT MONO (-563 812);
DISPLAY INVISIBLE (-563 812);
FORCEPROP 1 LASTPIN (-375 800) $PN 2
J 0
(-413 812);
DISPLAY 0.787234 (-413 812);
PAINT MONO (-413 812);
DISPLAY INVISIBLE (-413 812);
FORCEADD Q_RES..1
(-800 2100);
FORCEPROP 1 LAST PART_NUMBER CS00002JB13
J 0
(-700 2050);
DISPLAY 0.638298 (-700 2050);
DISPLAY INVISIBLE (-700 2050);
FORCEPROP 1 LAST MATERIAL CHIP
J 0
(-1000 2050);
DISPLAY 0.638298 (-1000 2050);
FORCEPROP 1 LAST WATTAGE 1/16W
J 2
(-225 2100);
DISPLAY 0.638298 (-225 2100);
FORCEPROP 1 LAST PACK_TYPE 0402LF
J 0
(-575 2100);
DISPLAY 0.638298 (-575 2100);
FORCEPROP 1 LAST TOLERANCE 5%
J 0
(-650 2100);
DISPLAY 0.638298 (-650 2100);
FORCEPROP 1 LAST VALUE 0
J 2
(-675 2100);
DISPLAY 0.638298 (-675 2100);
FORCEPROP 1 LAST LOCATION PR4255
J 0
(-1075 2100);
DISPLAY 0.787234 (-1075 2100);
FORCEPROP 1 LASTPIN (-900 2100) $PN 1
J 0
(-888 2112);
DISPLAY 0.638298 (-888 2112);
PAINT MONO (-888 2112);
FORCEPROP 1 LASTPIN (-700 2100) $PN 2
J 0
(-738 2112);
DISPLAY 0.787234 (-738 2112);
PAINT MONO (-738 2112);
FORCEPROP 2 LAST CDS_LIB pure_quanta
J 0
(-800 2100);
DISPLAY INVISIBLE (-800 2100);
FORCEPROP 1 LAST PATH I62
J 0
(-850 2250);
DISPLAY 0.978723 (-850 2250);
PAINT WHITE (-850 2250);
DISPLAY INVISIBLE (-850 2250);
FORCEPROP 0 LAST $SEC 1
J 0
(-225 2150);
DISPLAY 0.680851 (-225 2150);
PAINT MONO (-225 2150);
DISPLAY INVISIBLE (-225 2150);
FORCEPROP 0 LAST CDS_SEC 1
J 0
(-225 2150);
DISPLAY 1.021277 (-225 2150);
DISPLAY INVISIBLE (-225 2150);
FORCEADD Q_RES..1
(-800 1650);
FORCEPROP 1 LAST PART_NUMBER CS00002JB13
J 0
(-700 1600);
DISPLAY 0.638298 (-700 1600);
DISPLAY INVISIBLE (-700 1600);
FORCEPROP 1 LAST MATERIAL CHIP
J 0
(-1000 1600);
DISPLAY 0.638298 (-1000 1600);
FORCEPROP 1 LAST WATTAGE 1/16W
J 2
(-225 1650);
DISPLAY 0.638298 (-225 1650);
FORCEPROP 1 LAST PACK_TYPE 0402LF
J 0
(-575 1650);
DISPLAY 0.638298 (-575 1650);
FORCEPROP 1 LAST TOLERANCE 5%
J 0
(-650 1650);
DISPLAY 0.638298 (-650 1650);
FORCEPROP 1 LAST VALUE 0
J 2
(-675 1650);
DISPLAY 0.638298 (-675 1650);
FORCEPROP 1 LAST LOCATION PR4256
J 0
(-1075 1650);
DISPLAY 0.787234 (-1075 1650);
FORCEPROP 1 LASTPIN (-900 1650) $PN 1
J 0
(-888 1662);
DISPLAY 0.787234 (-888 1662);
PAINT MONO (-888 1662);
FORCEPROP 1 LASTPIN (-700 1650) $PN 2
J 0
(-738 1662);
DISPLAY 0.787234 (-738 1662);
PAINT MONO (-738 1662);
FORCEPROP 2 LAST CDS_LIB pure_quanta
J 0
(-800 1650);
DISPLAY INVISIBLE (-800 1650);
FORCEPROP 1 LAST PATH I63
J 0
(-850 1800);
DISPLAY 0.978723 (-850 1800);
PAINT WHITE (-850 1800);
DISPLAY INVISIBLE (-850 1800);
FORCEPROP 0 LAST $SEC 1
J 0
(-225 1700);
DISPLAY 0.680851 (-225 1700);
PAINT MONO (-225 1700);
DISPLAY INVISIBLE (-225 1700);
FORCEPROP 0 LAST CDS_SEC 1
J 0
(-225 1700);
DISPLAY 1.021277 (-225 1700);
DISPLAY INVISIBLE (-225 1700);
FORCEADD Q_RES..1
(-800 3450);
FORCEPROP 1 LAST PART_NUMBER CS00002JB13
J 0
(-700 3400);
DISPLAY 0.638298 (-700 3400);
DISPLAY INVISIBLE (-700 3400);
FORCEPROP 1 LAST MATERIAL CHIP
J 0
(-1000 3400);
DISPLAY 0.638298 (-1000 3400);
FORCEPROP 1 LAST WATTAGE 1/16W
J 2
(-225 3450);
DISPLAY 0.638298 (-225 3450);
FORCEPROP 1 LAST PACK_TYPE 0402LF
J 0
(-575 3450);
DISPLAY 0.638298 (-575 3450);
FORCEPROP 1 LAST TOLERANCE 5%
J 0
(-650 3450);
DISPLAY 0.638298 (-650 3450);
FORCEPROP 1 LAST VALUE 0
J 2
(-675 3450);
DISPLAY 0.638298 (-675 3450);
FORCEPROP 1 LAST LOCATION PR4252
J 0
(-1075 3450);
DISPLAY 0.787234 (-1075 3450);
FORCEPROP 1 LASTPIN (-900 3450) $PN 1
J 0
(-888 3462);
DISPLAY 0.787234 (-888 3462);
PAINT MONO (-888 3462);
FORCEPROP 1 LASTPIN (-700 3450) $PN 2
J 0
(-738 3462);
DISPLAY 0.787234 (-738 3462);
PAINT MONO (-738 3462);
FORCEPROP 2 LAST CDS_LIB pure_quanta
J 0
(-800 3450);
DISPLAY INVISIBLE (-800 3450);
FORCEPROP 1 LAST PATH I64
J 0
(-850 3600);
DISPLAY 0.978723 (-850 3600);
PAINT WHITE (-850 3600);
DISPLAY INVISIBLE (-850 3600);
FORCEPROP 0 LAST $SEC 1
J 0
(-225 3500);
DISPLAY 0.680851 (-225 3500);
PAINT MONO (-225 3500);
DISPLAY INVISIBLE (-225 3500);
FORCEPROP 0 LAST CDS_SEC 1
J 0
(-225 3500);
DISPLAY 1.021277 (-225 3500);
DISPLAY INVISIBLE (-225 3500);
FORCEADD Q_RES..1
(-800 3000);
FORCEPROP 1 LAST PART_NUMBER CS00002JB13
J 0
(-700 2950);
DISPLAY 0.638298 (-700 2950);
DISPLAY INVISIBLE (-700 2950);
FORCEPROP 1 LAST WATTAGE 1/16W
J 2
(-225 3000);
DISPLAY 0.638298 (-225 3000);
FORCEPROP 1 LAST PACK_TYPE 0402LF
J 0
(-575 3000);
DISPLAY 0.638298 (-575 3000);
FORCEPROP 1 LAST TOLERANCE 5%
J 0
(-650 3000);
DISPLAY 0.638298 (-650 3000);
FORCEPROP 1 LAST VALUE 0
J 2
(-675 3000);
DISPLAY 0.638298 (-675 3000);
FORCEPROP 1 LAST MATERIAL CHIP
J 0
(-1000 2950);
DISPLAY 0.638298 (-1000 2950);
FORCEPROP 1 LAST LOCATION PR4253
J 0
(-1075 3000);
DISPLAY 0.787234 (-1075 3000);
FORCEPROP 1 LASTPIN (-900 3000) $PN 1
J 0
(-888 3012);
DISPLAY 0.787234 (-888 3012);
PAINT MONO (-888 3012);
FORCEPROP 1 LASTPIN (-700 3000) $PN 2
J 0
(-738 3012);
DISPLAY 0.787234 (-738 3012);
PAINT MONO (-738 3012);
FORCEPROP 2 LAST CDS_LIB pure_quanta
J 0
(-800 3000);
DISPLAY INVISIBLE (-800 3000);
FORCEPROP 1 LAST PATH I65
J 0
(-850 3150);
DISPLAY 0.978723 (-850 3150);
PAINT WHITE (-850 3150);
DISPLAY INVISIBLE (-850 3150);
FORCEPROP 0 LAST $SEC 1
J 0
(-225 3050);
DISPLAY 0.680851 (-225 3050);
PAINT MONO (-225 3050);
DISPLAY INVISIBLE (-225 3050);
FORCEPROP 0 LAST CDS_SEC 1
J 0
(-225 3050);
DISPLAY 1.021277 (-225 3050);
DISPLAY INVISIBLE (-225 3050);
FORCEADD Q_RES..1
(-800 2550);
FORCEPROP 1 LAST PART_NUMBER CS00002JB13
J 0
(-700 2500);
DISPLAY 0.638298 (-700 2500);
DISPLAY INVISIBLE (-700 2500);
FORCEPROP 1 LAST WATTAGE 1/16W
J 2
(-225 2550);
DISPLAY 0.638298 (-225 2550);
FORCEPROP 1 LAST MATERIAL CHIP
J 0
(-1000 2500);
DISPLAY 0.638298 (-1000 2500);
FORCEPROP 1 LAST TOLERANCE 5%
J 0
(-650 2550);
DISPLAY 0.638298 (-650 2550);
FORCEPROP 1 LAST VALUE 0
J 2
(-675 2550);
DISPLAY 0.638298 (-675 2550);
FORCEPROP 1 LAST PACK_TYPE 0402LF
J 0
(-575 2550);
DISPLAY 0.638298 (-575 2550);
FORCEPROP 1 LAST LOCATION PR4254
J 0
(-1075 2550);
DISPLAY 0.787234 (-1075 2550);
FORCEPROP 1 LASTPIN (-900 2550) $PN 1
J 0
(-888 2562);
DISPLAY 0.787234 (-888 2562);
PAINT MONO (-888 2562);
FORCEPROP 1 LASTPIN (-700 2550) $PN 2
J 0
(-738 2562);
DISPLAY 0.787234 (-738 2562);
PAINT MONO (-738 2562);
FORCEPROP 2 LAST CDS_LIB pure_quanta
J 0
(-800 2550);
DISPLAY INVISIBLE (-800 2550);
FORCEPROP 1 LAST PATH I66
J 0
(-850 2700);
DISPLAY 0.978723 (-850 2700);
PAINT WHITE (-850 2700);
DISPLAY INVISIBLE (-850 2700);
FORCEPROP 0 LAST $SEC 1
J 0
(-225 2600);
DISPLAY 0.680851 (-225 2600);
PAINT MONO (-225 2600);
DISPLAY INVISIBLE (-225 2600);
FORCEPROP 0 LAST CDS_SEC 1
J 0
(-225 2600);
DISPLAY 1.021277 (-225 2600);
DISPLAY INVISIBLE (-225 2600);
FORCEADD UNIVERSAL_GND..1
R 1
(-3775 5600);
FORCEPROP 3 LASTPIN (-3825 5600) SIG_NAME GND\g
J 0
(-3815 5610);
DISPLAY 0.659574 (-3815 5610);
PAINT MONO (-3815 5610);
DISPLAY INVISIBLE (-3815 5610);
FORCEPROP 1 LAST HDL_POWER GND
R 1
J 1
(-3700 5625);
DISPLAY 0.872340 (-3700 5625);
PAINT GREEN (-3700 5625);
DISPLAY INVISIBLE (-3700 5625);
FORCEPROP 2 LAST CDS_LIB logical_power
J 0
(-3775 5600);
PAINT MONO (-3775 5600);
DISPLAY INVISIBLE (-3775 5600);
FORCEPROP 1 LAST PATH I67
R 1
J 0
(-3775 5675);
DISPLAY 0.872340 (-3775 5675);
PAINT AQUA (-3775 5675);
DISPLAY INVISIBLE (-3775 5675);
FORCEADD Q_CAP..1
(-1700 4775);
FORCEPROP 1 LAST PART_NUMBER CH6101MEB03
J 0
(-1650 4600);
DISPLAY 0.617021 (-1650 4600);
PAINT BLUE (-1650 4600);
DISPLAY INVISIBLE (-1650 4600);
FORCEPROP 1 LAST PACK_TYPE C0402
J 0
(-1650 4650);
DISPLAY 0.617021 (-1650 4650);
PAINT SKYBLUE (-1650 4650);
FORCEPROP 1 LAST VALUE 10UF
J 0
(-1650 4850);
DISPLAY 0.617021 (-1650 4850);
PAINT SKYBLUE (-1650 4850);
FORCEPROP 1 LAST TOLERANCE 20%
J 0
(-1650 4750);
DISPLAY 0.617021 (-1650 4750);
PAINT SKYBLUE (-1650 4750);
FORCEPROP 1 LAST MATERIAL X6S
J 0
(-1650 4700);
DISPLAY 0.617021 (-1650 4700);
PAINT SKYBLUE (-1650 4700);
FORCEPROP 1 LAST VOLTAGE 6.3V
J 0
(-1650 4800);
DISPLAY 0.617021 (-1650 4800);
PAINT SKYBLUE (-1650 4800);
FORCEPROP 1 LAST LOCATION PC392
J 0
(-1650 4900);
DISPLAY 0.617021 (-1650 4900);
PAINT AQUA (-1650 4900);
FORCEPROP 1 LASTPIN (-1700 4875) $PN 1
J 0
(-1690 4855);
DISPLAY 0.617021 (-1690 4855);
PAINT MONO (-1690 4855);
FORCEPROP 1 LASTPIN (-1700 4675) $PN 2
J 0
(-1690 4655);
DISPLAY 0.617021 (-1690 4655);
PAINT MONO (-1690 4655);
FORCEPROP 2 LAST CDS_LIB pure_quanta
J 0
(-1700 4775);
DISPLAY INVISIBLE (-1700 4775);
FORCEPROP 1 LAST PATH I68
J 0
(-1650 4925);
DISPLAY 0.978723 (-1650 4925);
PAINT WHITE (-1650 4925);
DISPLAY INVISIBLE (-1650 4925);
FORCEPROP 1 LAST LOCATION PC392
J 0
(-1650 4950);
DISPLAY 1.021277 (-1650 4950);
PAINT AQUA (-1650 4950);
DISPLAY INVISIBLE (-1650 4950);
FORCEPROP 0 LAST $SEC 1
J 0
(-1650 4950);
DISPLAY 0.680851 (-1650 4950);
PAINT MONO (-1650 4950);
DISPLAY INVISIBLE (-1650 4950);
FORCEPROP 0 LAST CDS_SEC 1
J 0
(-1650 4950);
DISPLAY 1.021277 (-1650 4950);
DISPLAY INVISIBLE (-1650 4950);
FORCEADD Q_CAP..1
(-1700 5250);
FORCEPROP 1 LAST PART_NUMBER CH4106K1B01
J 0
(-1650 5075);
DISPLAY 0.617021 (-1650 5075);
PAINT BLUE (-1650 5075);
DISPLAY INVISIBLE (-1650 5075);
FORCEPROP 1 LAST VOLTAGE 50V
J 0
(-1650 5275);
DISPLAY 0.617021 (-1650 5275);
PAINT SKYBLUE (-1650 5275);
FORCEPROP 1 LAST VALUE 100NF
J 0
(-1650 5325);
DISPLAY 0.617021 (-1650 5325);
PAINT SKYBLUE (-1650 5325);
FORCEPROP 1 LAST PACK_TYPE C0402
J 0
(-1650 5125);
DISPLAY 0.617021 (-1650 5125);
PAINT SKYBLUE (-1650 5125);
FORCEPROP 1 LAST MATERIAL EMPTY
J 0
(-1650 5175);
DISPLAY 0.617021 (-1650 5175);
PAINT RED (-1650 5175);
FORCEPROP 1 LAST TOLERANCE 10%
J 0
(-1650 5225);
DISPLAY 0.617021 (-1650 5225);
PAINT SKYBLUE (-1650 5225);
FORCEPROP 1 LAST LOCATION PC391
J 0
(-1650 5375);
DISPLAY 0.617021 (-1650 5375);
PAINT AQUA (-1650 5375);
FORCEPROP 1 LASTPIN (-1700 5350) $PN 1
J 0
(-1690 5330);
DISPLAY 0.617021 (-1690 5330);
PAINT MONO (-1690 5330);
FORCEPROP 1 LASTPIN (-1700 5150) $PN 2
J 0
(-1690 5130);
DISPLAY 0.617021 (-1690 5130);
PAINT MONO (-1690 5130);
FORCEPROP 2 LAST CDS_LIB pure_quanta
J 0
(-1700 5250);
DISPLAY INVISIBLE (-1700 5250);
FORCEPROP 1 LAST PATH I69
J 0
(-1650 5400);
DISPLAY 0.978723 (-1650 5400);
PAINT WHITE (-1650 5400);
DISPLAY INVISIBLE (-1650 5400);
FORCEPROP 1 LAST LOCATION PC391
J 0
(-1650 5425);
DISPLAY 1.021277 (-1650 5425);
PAINT AQUA (-1650 5425);
DISPLAY INVISIBLE (-1650 5425);
FORCEPROP 0 LAST $SEC 1
J 0
(-1650 5425);
DISPLAY 0.680851 (-1650 5425);
PAINT MONO (-1650 5425);
DISPLAY INVISIBLE (-1650 5425);
FORCEPROP 0 LAST CDS_SEC 1
J 0
(-1650 5425);
DISPLAY 1.021277 (-1650 5425);
DISPLAY INVISIBLE (-1650 5425);
FORCEADD Q_RES..1
(-800 3900);
FORCEPROP 1 LAST PART_NUMBER CS00002JB13
J 0
(-700 3850);
DISPLAY 0.638298 (-700 3850);
DISPLAY INVISIBLE (-700 3850);
FORCEPROP 1 LAST MATERIAL CHIP
J 0
(-1000 3850);
DISPLAY 0.638298 (-1000 3850);
FORCEPROP 1 LAST VALUE 0
J 2
(-675 3900);
DISPLAY 0.638298 (-675 3900);
FORCEPROP 1 LAST TOLERANCE 5%
J 0
(-650 3900);
DISPLAY 0.638298 (-650 3900);
FORCEPROP 1 LAST WATTAGE 1/16W
J 2
(-225 3900);
DISPLAY 0.638298 (-225 3900);
FORCEPROP 1 LAST PACK_TYPE 0402LF
J 0
(-575 3900);
DISPLAY 0.638298 (-575 3900);
FORCEPROP 1 LAST LOCATION PR4251
J 0
(-1075 3900);
DISPLAY 0.787234 (-1075 3900);
FORCEPROP 1 LASTPIN (-900 3900) $PN 1
J 0
(-888 3912);
DISPLAY 0.787234 (-888 3912);
PAINT MONO (-888 3912);
FORCEPROP 1 LASTPIN (-700 3900) $PN 2
J 0
(-738 3912);
DISPLAY 0.787234 (-738 3912);
PAINT MONO (-738 3912);
FORCEPROP 2 LAST CDS_LIB pure_quanta
J 0
(-800 3900);
DISPLAY INVISIBLE (-800 3900);
FORCEPROP 1 LAST PATH I70
J 0
(-850 4050);
DISPLAY 0.978723 (-850 4050);
PAINT WHITE (-850 4050);
DISPLAY INVISIBLE (-850 4050);
FORCEPROP 0 LAST $SEC 1
J 0
(-225 3950);
DISPLAY 0.680851 (-225 3950);
PAINT MONO (-225 3950);
DISPLAY INVISIBLE (-225 3950);
FORCEPROP 0 LAST CDS_SEC 1
J 0
(-225 3950);
DISPLAY 1.021277 (-225 3950);
DISPLAY INVISIBLE (-225 3950);
FORCEADD OFFPAGE..4
(-1000 4350);
FORCEPROP 2 LAST $XR0 297 
J 0
(-814 4350);
DISPLAY 0.638298 (-814 4350);
PAINT MONO (-814 4350);
FORCEPROP 1 LAST COMMENT_BODY TRUE
J 0
(-1025 4250);
DISPLAY 0.872340 (-1025 4250);
PAINT GREEN (-1025 4250);
DISPLAY INVISIBLE (-1025 4250);
FORCEPROP 1 LAST OFFPAGE TRUE
J 0
(-675 4225);
DISPLAY 0.872340 (-675 4225);
PAINT GREEN (-675 4225);
DISPLAY INVISIBLE (-675 4225);
FORCEPROP 2 LAST CDS_LIB standard
J 0
(-1000 4350);
DISPLAY INVISIBLE (-1000 4350);
FORCEPROP 2 LAST PATH I71
J 0
(-800 4400);
DISPLAY 1.021277 (-800 4400);
DISPLAY INVISIBLE (-800 4400);
FORCEADD OFFPAGE..2
(-1000 4450);
FORCEPROP 2 LAST $XR0 297 
J 0
(-811 4450);
DISPLAY 0.638298 (-811 4450);
PAINT MONO (-811 4450);
FORCEPROP 1 LAST COMMENT_BODY TRUE
J 0
(-1045 4355);
DISPLAY 0.872340 (-1045 4355);
PAINT GREEN (-1045 4355);
DISPLAY INVISIBLE (-1045 4355);
FORCEPROP 1 LAST OFFPAGE TRUE
J 0
(-675 4325);
DISPLAY 0.872340 (-675 4325);
PAINT GREEN (-675 4325);
DISPLAY INVISIBLE (-675 4325);
FORCEPROP 2 LAST CDS_LIB standard
J 0
(-1000 4450);
DISPLAY INVISIBLE (-1000 4450);
FORCEPROP 2 LAST PATH I72
J 0
(-800 4500);
DISPLAY 1.021277 (-800 4500);
DISPLAY INVISIBLE (-800 4500);
FORCEADD UNIVERSAL_GND..1
R 3
(-850 4575);
FORCEPROP 3 LASTPIN (-900 4575) SIG_NAME GND\g
J 0
(-890 4585);
DISPLAY 0.659574 (-890 4585);
PAINT MONO (-890 4585);
DISPLAY INVISIBLE (-890 4585);
FORCEPROP 1 LAST HDL_POWER GND
R 1
J 1
(-775 4550);
DISPLAY 0.872340 (-775 4550);
PAINT GREEN (-775 4550);
DISPLAY INVISIBLE (-775 4550);
FORCEPROP 2 LAST CDS_LIB logical_power
J 0
(-850 4575);
PAINT MONO (-850 4575);
DISPLAY INVISIBLE (-850 4575);
FORCEPROP 1 LAST PATH I73
R 1
J 2
(-850 4500);
DISPLAY 0.872340 (-850 4500);
PAINT AQUA (-850 4500);
DISPLAY INVISIBLE (-850 4500);
FORCEADD Q_CAP..1
(-1300 4775);
FORCEPROP 1 LAST PART_NUMBER CH5103KEB01
J 0
(-1250 4600);
DISPLAY 0.617021 (-1250 4600);
PAINT BLUE (-1250 4600);
DISPLAY INVISIBLE (-1250 4600);
FORCEPROP 1 LAST MATERIAL X6S
J 0
(-1250 4700);
DISPLAY 0.617021 (-1250 4700);
PAINT SKYBLUE (-1250 4700);
FORCEPROP 1 LAST VALUE 1UF
J 0
(-1250 4850);
DISPLAY 0.617021 (-1250 4850);
PAINT SKYBLUE (-1250 4850);
FORCEPROP 1 LAST VOLTAGE 16V
J 0
(-1250 4800);
DISPLAY 0.617021 (-1250 4800);
PAINT SKYBLUE (-1250 4800);
FORCEPROP 1 LAST PACK_TYPE C0402
J 0
(-1250 4650);
DISPLAY 0.617021 (-1250 4650);
PAINT SKYBLUE (-1250 4650);
FORCEPROP 1 LAST TOLERANCE 10%
J 0
(-1250 4750);
DISPLAY 0.617021 (-1250 4750);
PAINT SKYBLUE (-1250 4750);
FORCEPROP 1 LAST LOCATION PC1289
J 0
(-1250 4900);
DISPLAY 0.617021 (-1250 4900);
PAINT AQUA (-1250 4900);
FORCEPROP 1 LASTPIN (-1300 4875) $PN 1
J 0
(-1290 4855);
DISPLAY 0.617021 (-1290 4855);
FORCEPROP 1 LASTPIN (-1300 4675) $PN 2
J 0
(-1290 4655);
DISPLAY 0.617021 (-1290 4655);
FORCEPROP 2 LAST CDS_LIB pure_quanta
J 0
(-1300 4775);
PAINT MONO (-1300 4775);
DISPLAY INVISIBLE (-1300 4775);
FORCEPROP 1 LAST PATH I74
J 0
(-1250 4925);
DISPLAY 0.978723 (-1250 4925);
PAINT WHITE (-1250 4925);
DISPLAY INVISIBLE (-1250 4925);
FORCEPROP 2 LAST $SEC 1
J 0
(-1250 4975);
DISPLAY 0.680851 (-1250 4975);
PAINT MONO (-1250 4975);
DISPLAY INVISIBLE (-1250 4975);
FORCEPROP 2 LAST CDS_SEC 1
J 0
(-1250 4975);
DISPLAY 1.021277 (-1250 4975);
DISPLAY INVISIBLE (-1250 4975);
FORCEADD UNIVERSAL_GND..1
R 3
(-850 5050);
FORCEPROP 3 LASTPIN (-900 5050) SIG_NAME GND\g
J 0
(-890 5060);
DISPLAY 0.659574 (-890 5060);
PAINT MONO (-890 5060);
DISPLAY INVISIBLE (-890 5060);
FORCEPROP 1 LAST HDL_POWER GND
R 1
J 1
(-775 5025);
DISPLAY 0.872340 (-775 5025);
PAINT GREEN (-775 5025);
DISPLAY INVISIBLE (-775 5025);
FORCEPROP 2 LAST CDS_LIB logical_power
J 0
(-850 5050);
PAINT MONO (-850 5050);
DISPLAY INVISIBLE (-850 5050);
FORCEPROP 1 LAST PATH I75
R 1
J 2
(-850 4975);
DISPLAY 0.872340 (-850 4975);
PAINT AQUA (-850 4975);
DISPLAY INVISIBLE (-850 4975);
FORCEADD OFFPAGE..2
(-850 4975);
FORCEPROP 2 LAST $XR1 297 
J 0
(-541 4975);
DISPLAY 0.638298 (-541 4975);
PAINT MONO (-541 4975);
FORCEPROP 2 LAST $XR0 296 
J 0
(-661 4975);
DISPLAY 0.638298 (-661 4975);
PAINT MONO (-661 4975);
FORCEPROP 1 LAST COMMENT_BODY TRUE
J 0
(-895 4880);
DISPLAY 0.872340 (-895 4880);
PAINT GREEN (-895 4880);
DISPLAY INVISIBLE (-895 4880);
FORCEPROP 1 LAST OFFPAGE TRUE
J 0
(-525 4850);
DISPLAY 0.872340 (-525 4850);
PAINT GREEN (-525 4850);
DISPLAY INVISIBLE (-525 4850);
FORCEPROP 2 LAST CDS_LIB standard
J 0
(-850 4975);
DISPLAY INVISIBLE (-850 4975);
FORCEPROP 2 LAST PATH I76
J 0
(-525 5025);
DISPLAY 1.021277 (-525 5025);
DISPLAY INVISIBLE (-525 5025);
FORCEADD Q_CAP..1
(-1300 5250);
FORCEPROP 1 LAST PART_NUMBER CH5103KEB01
J 0
(-1250 5075);
DISPLAY 0.617021 (-1250 5075);
PAINT BLUE (-1250 5075);
DISPLAY INVISIBLE (-1250 5075);
FORCEPROP 1 LAST MATERIAL X6S
J 0
(-1250 5175);
DISPLAY 0.617021 (-1250 5175);
PAINT SKYBLUE (-1250 5175);
FORCEPROP 1 LAST TOLERANCE 10%
J 0
(-1250 5225);
DISPLAY 0.617021 (-1250 5225);
PAINT SKYBLUE (-1250 5225);
FORCEPROP 1 LAST PACK_TYPE C0402
J 0
(-1250 5125);
DISPLAY 0.617021 (-1250 5125);
PAINT SKYBLUE (-1250 5125);
FORCEPROP 1 LAST VALUE 1UF
J 0
(-1250 5325);
DISPLAY 0.617021 (-1250 5325);
PAINT SKYBLUE (-1250 5325);
FORCEPROP 1 LAST VOLTAGE 16V
J 0
(-1250 5275);
DISPLAY 0.617021 (-1250 5275);
PAINT SKYBLUE (-1250 5275);
FORCEPROP 1 LAST LOCATION PC394
J 0
(-1250 5375);
DISPLAY 0.617021 (-1250 5375);
PAINT AQUA (-1250 5375);
FORCEPROP 1 LASTPIN (-1300 5350) $PN 1
J 0
(-1290 5330);
DISPLAY 0.617021 (-1290 5330);
PAINT MONO (-1290 5330);
FORCEPROP 1 LASTPIN (-1300 5150) $PN 2
J 0
(-1290 5130);
DISPLAY 0.617021 (-1290 5130);
PAINT MONO (-1290 5130);
FORCEPROP 2 LAST CDS_LIB pure_quanta
J 0
(-1300 5250);
DISPLAY INVISIBLE (-1300 5250);
FORCEPROP 1 LAST PATH I77
J 0
(-1250 5400);
DISPLAY 0.978723 (-1250 5400);
PAINT WHITE (-1250 5400);
DISPLAY INVISIBLE (-1250 5400);
FORCEPROP 1 LAST LOCATION PC394
J 0
(-1250 5425);
DISPLAY 1.021277 (-1250 5425);
PAINT AQUA (-1250 5425);
DISPLAY INVISIBLE (-1250 5425);
FORCEPROP 0 LAST $SEC 1
J 0
(-1250 5425);
DISPLAY 0.680851 (-1250 5425);
PAINT MONO (-1250 5425);
DISPLAY INVISIBLE (-1250 5425);
FORCEPROP 0 LAST CDS_SEC 1
J 0
(-1250 5425);
DISPLAY 1.021277 (-1250 5425);
DISPLAY INVISIBLE (-1250 5425);
FORCEADD Q_RES..1
(-975 5450);
FORCEPROP 1 LAST PART_NUMBER CS-1002FB04
J 0
(-825 5400);
DISPLAY 0.617021 (-825 5400);
PAINT BLUE (-825 5400);
DISPLAY INVISIBLE (-825 5400);
FORCEPROP 1 LAST VALUE 1
J 2
(-800 5450);
DISPLAY 0.617021 (-800 5450);
PAINT SKYBLUE (-800 5450);
FORCEPROP 1 LAST TOLERANCE 1%
J 0
(-775 5450);
DISPLAY 0.617021 (-775 5450);
PAINT SKYBLUE (-775 5450);
FORCEPROP 1 LAST WATTAGE 1/16W
J 2
(-525 5350);
DISPLAY 0.617021 (-525 5350);
PAINT SKYBLUE (-525 5350);
FORCEPROP 1 LAST PACK_TYPE 0402LF
J 0
(-825 5350);
DISPLAY 0.617021 (-825 5350);
PAINT SKYBLUE (-825 5350);
FORCEPROP 1 LAST MATERIAL CHIP
J 0
(-675 5450);
DISPLAY 0.617021 (-675 5450);
PAINT SKYBLUE (-675 5450);
FORCEPROP 1 LAST LOCATION PR220
J 0
(-1225 5450);
DISPLAY 0.617021 (-1225 5450);
PAINT AQUA (-1225 5450);
FORCEPROP 1 LASTPIN (-1075 5450) $PN 1
J 0
(-1063 5462);
DISPLAY 0.617021 (-1063 5462);
PAINT MONO (-1063 5462);
FORCEPROP 1 LASTPIN (-875 5450) $PN 2
J 0
(-913 5462);
DISPLAY 0.617021 (-913 5462);
PAINT MONO (-913 5462);
FORCEPROP 2 LAST CDS_LIB pure_quanta
J 0
(-975 5450);
DISPLAY INVISIBLE (-975 5450);
FORCEPROP 1 LAST PATH I78
J 0
(-1025 5600);
DISPLAY 0.978723 (-1025 5600);
PAINT WHITE (-1025 5600);
DISPLAY INVISIBLE (-1025 5600);
FORCEPROP 1 LAST LOCATION PR220
J 0
(-1025 5550);
DISPLAY 1.021277 (-1025 5550);
PAINT AQUA (-1025 5550);
DISPLAY INVISIBLE (-1025 5550);
FORCEPROP 0 LAST $SEC 1
J 0
(-1025 5550);
DISPLAY 0.680851 (-1025 5550);
PAINT MONO (-1025 5550);
DISPLAY INVISIBLE (-1025 5550);
FORCEPROP 0 LAST CDS_SEC 1
J 0
(-1025 5550);
DISPLAY 1.021277 (-1025 5550);
DISPLAY INVISIBLE (-1025 5550);
FORCEADD VCC15..1
(-500 5575);
FORCEPROP 3 LASTPIN (-500 5525) SIG_NAME P3V3_AUX\g
J 0
(-490 5535);
DISPLAY 0.659574 (-490 5535);
PAINT MONO (-490 5535);
DISPLAY INVISIBLE (-490 5535);
FORCEPROP 1 LAST HDL_POWER P3V3_AUX
J 1
(-500 5625);
DISPLAY 0.617021 (-500 5625);
PAINT GREEN (-500 5625);
FORCEPROP 2 LAST CDS_LIB logical_power
J 0
(-500 5575);
DISPLAY INVISIBLE (-500 5575);
FORCEPROP 1 LAST PATH I79
J 0
(-450 5600);
DISPLAY 0.872340 (-450 5600);
PAINT AQUA (-450 5600);
DISPLAY INVISIBLE (-450 5600);
FORCEADD Q_RES..1
(-6200 350);
FORCEPROP 1 LAST PART_NUMBER CS32802FB05
J 0
(-6300 425);
DISPLAY 0.617021 (-6300 425);
PAINT BLUE (-6300 425);
DISPLAY INVISIBLE (-6300 425);
FORCEPROP 1 LAST TOLERANCE 1%
J 0
(-5950 350);
DISPLAY 0.617021 (-5950 350);
PAINT SKYBLUE (-5950 350);
FORCEPROP 1 LAST PACK_TYPE 0402LF
J 0
(-5875 350);
DISPLAY 0.617021 (-5875 350);
PAINT SKYBLUE (-5875 350);
FORCEPROP 1 LAST VALUE 28K
J 2
(-5975 350);
DISPLAY 0.617021 (-5975 350);
PAINT SKYBLUE (-5975 350);
FORCEPROP 1 LAST WATTAGE 1/16W
J 2
(-5950 475);
DISPLAY 0.617021 (-5950 475);
PAINT SKYBLUE (-5950 475);
FORCEPROP 1 LAST MATERIAL EMPTY
J 0
(-6300 475);
DISPLAY 0.617021 (-6300 475);
PAINT RED (-6300 475);
FORCEPROP 1 LAST LOCATION PR202
J 0
(-6450 350);
DISPLAY 0.617021 (-6450 350);
PAINT AQUA (-6450 350);
FORCEPROP 1 LASTPIN (-6300 350) $PN 1
J 0
(-6288 362);
DISPLAY 0.617021 (-6288 362);
PAINT MONO (-6288 362);
FORCEPROP 1 LASTPIN (-6100 350) $PN 2
J 0
(-6138 362);
DISPLAY 0.617021 (-6138 362);
PAINT MONO (-6138 362);
FORCEPROP 2 LAST CDS_LIB pure_quanta
J 0
(-6200 350);
DISPLAY INVISIBLE (-6200 350);
FORCEPROP 1 LAST PATH I8
J 0
(-6250 500);
DISPLAY 0.978723 (-6250 500);
PAINT WHITE (-6250 500);
DISPLAY INVISIBLE (-6250 500);
FORCEPROP 1 LAST LOCATION PR202
J 0
(-6275 475);
DISPLAY 1.021277 (-6275 475);
PAINT AQUA (-6275 475);
DISPLAY INVISIBLE (-6275 475);
FORCEPROP 0 LAST $SEC 1
J 0
(-6275 475);
DISPLAY 0.680851 (-6275 475);
PAINT MONO (-6275 475);
DISPLAY INVISIBLE (-6275 475);
FORCEPROP 0 LAST CDS_SEC 1
J 0
(-6275 475);
DISPLAY 1.021277 (-6275 475);
DISPLAY INVISIBLE (-6275 475);
FORCEADD UNIVERSAL_GND..1
(-175 -200);
FORCEPROP 3 LASTPIN (-175 -150) SIG_NAME GND\g
J 0
(-165 -140);
DISPLAY 0.659574 (-165 -140);
PAINT MONO (-165 -140);
DISPLAY INVISIBLE (-165 -140);
FORCEPROP 1 LAST HDL_POWER GND
J 1
(-150 -275);
DISPLAY 0.872340 (-150 -275);
PAINT GREEN (-150 -275);
DISPLAY INVISIBLE (-150 -275);
FORCEPROP 2 LAST CDS_LIB logical_power
J 0
(-175 -200);
DISPLAY INVISIBLE (-175 -200);
FORCEPROP 1 LAST PATH I80
J 0
(-100 -200);
DISPLAY 0.872340 (-100 -200);
PAINT AQUA (-100 -200);
DISPLAY INVISIBLE (-100 -200);
FORCEADD Q_RES..2
(-175 50);
FORCEPROP 1 LAST PART_NUMBER CS31002FB08
J 0
(-135 -75);
DISPLAY 0.617021 (-135 -75);
PAINT BLUE (-135 -75);
DISPLAY INVISIBLE (-135 -75);
FORCEPROP 1 LAST PACK_TYPE 0402LF
J 0
(-135 -125);
DISPLAY 0.617021 (-135 -125);
PAINT SKYBLUE (-135 -125);
FORCEPROP 1 LAST WATTAGE 1/16W
J 0
(-135 25);
DISPLAY 0.617021 (-135 25);
PAINT SKYBLUE (-135 25);
FORCEPROP 1 LAST TOLERANCE 1%
J 0
(-130 75);
DISPLAY 0.617021 (-130 75);
PAINT SKYBLUE (-130 75);
FORCEPROP 1 LAST MATERIAL EMPTY
J 0
(-135 -25);
DISPLAY 0.617021 (-135 -25);
PAINT RED (-135 -25);
FORCEPROP 1 LAST VALUE 10K
J 0
(-130 125);
DISPLAY 0.617021 (-130 125);
PAINT SKYBLUE (-130 125);
FORCEPROP 1 LAST LOCATION PR705
J 0
(-130 175);
DISPLAY 0.617021 (-130 175);
PAINT AQUA (-130 175);
FORCEPROP 2 LAST CDS_LIB pure_quanta
J 0
(-175 50);
DISPLAY INVISIBLE (-175 50);
FORCEPROP 1 LAST PATH I81
J 0
(-125 225);
DISPLAY 0.978723 (-125 225);
PAINT WHITE (-125 225);
DISPLAY INVISIBLE (-125 225);
FORCEPROP 0 LAST $SEC 1
J 0
(-125 225);
DISPLAY INVISIBLE (-125 225);
FORCEPROP 0 LAST CDS_SEC 1
J 0
(-125 225);
DISPLAY INVISIBLE (-125 225);
FORCEPROP 1 LASTPIN (-175 150) $PN 1
J 0
(-170 112);
DISPLAY 0.787234 (-170 112);
PAINT MONO (-170 112);
DISPLAY INVISIBLE (-170 112);
FORCEPROP 1 LASTPIN (-175 -50) $PN 2
J 0
(-170 -40);
DISPLAY 0.787234 (-170 -40);
PAINT MONO (-170 -40);
DISPLAY INVISIBLE (-170 -40);
FORCEADD UNIVERSAL_GND..1
(250 425);
FORCEPROP 3 LASTPIN (250 475) SIG_NAME GND\g
J 0
(260 485);
DISPLAY 0.659574 (260 485);
PAINT MONO (260 485);
DISPLAY INVISIBLE (260 485);
FORCEPROP 1 LAST HDL_POWER GND
J 1
(275 350);
DISPLAY 0.872340 (275 350);
PAINT GREEN (275 350);
DISPLAY INVISIBLE (275 350);
FORCEPROP 2 LAST CDS_LIB logical_power
J 0
(250 425);
PAINT MONO (250 425);
DISPLAY INVISIBLE (250 425);
FORCEPROP 1 LAST PATH I82
J 0
(325 425);
DISPLAY 0.872340 (325 425);
PAINT AQUA (325 425);
DISPLAY INVISIBLE (325 425);
FORCEADD OFFPAGE..4
(550 250);
FORCEPROP 2 LAST $XR0 297 
J 0
(736 250);
DISPLAY 0.638298 (736 250);
PAINT MONO (736 250);
FORCEPROP 1 LAST COMMENT_BODY TRUE
J 0
(525 150);
DISPLAY 0.872340 (525 150);
PAINT GREEN (525 150);
DISPLAY INVISIBLE (525 150);
FORCEPROP 1 LAST OFFPAGE TRUE
J 0
(875 125);
DISPLAY 0.872340 (875 125);
PAINT GREEN (875 125);
DISPLAY INVISIBLE (875 125);
FORCEPROP 2 LAST CDS_LIB standard
J 0
(550 250);
DISPLAY INVISIBLE (550 250);
FORCEPROP 2 LAST PATH I83
J 0
(750 300);
DISPLAY 1.021277 (750 300);
DISPLAY INVISIBLE (750 300);
FORCEADD UNIVERSAL_GND..1
(-175 1125);
FORCEPROP 3 LASTPIN (-175 1175) SIG_NAME GND\g
J 0
(-165 1185);
DISPLAY 0.659574 (-165 1185);
PAINT MONO (-165 1185);
DISPLAY INVISIBLE (-165 1185);
FORCEPROP 1 LAST HDL_POWER GND
J 1
(-150 1050);
DISPLAY 0.872340 (-150 1050);
PAINT GREEN (-150 1050);
DISPLAY INVISIBLE (-150 1050);
FORCEPROP 2 LAST CDS_LIB logical_power
J 0
(-175 1125);
DISPLAY INVISIBLE (-175 1125);
FORCEPROP 1 LAST PATH I84
J 0
(-100 1125);
DISPLAY 0.872340 (-100 1125);
PAINT AQUA (-100 1125);
DISPLAY INVISIBLE (-100 1125);
FORCEADD Q_RES..2
(100 1225);
FORCEPROP 1 LAST PART_NUMBER CS21002FB06
J 0
(125 1100);
DISPLAY 0.617021 (125 1100);
PAINT BLUE (125 1100);
DISPLAY INVISIBLE (125 1100);
FORCEPROP 1 LAST VALUE 1K
J 0
(130 1300);
DISPLAY 0.617021 (130 1300);
PAINT SKYBLUE (130 1300);
FORCEPROP 1 LAST WATTAGE 1/16W
J 0
(125 1200);
DISPLAY 0.617021 (125 1200);
PAINT SKYBLUE (125 1200);
FORCEPROP 1 LAST MATERIAL CHIP
J 0
(125 1150);
DISPLAY 0.617021 (125 1150);
PAINT SKYBLUE (125 1150);
FORCEPROP 1 LAST TOLERANCE 1%
J 0
(130 1250);
DISPLAY 0.617021 (130 1250);
PAINT SKYBLUE (130 1250);
FORCEPROP 1 LAST PACK_TYPE 0402LF
J 0
(125 1050);
DISPLAY 0.617021 (125 1050);
PAINT SKYBLUE (125 1050);
FORCEPROP 1 LAST LOCATION R223
J 0
(130 1350);
DISPLAY 0.617021 (130 1350);
PAINT AQUA (130 1350);
FORCEPROP 1 LASTPIN (100 1325) $PN 1
J 0
(105 1287);
DISPLAY 0.617021 (105 1287);
PAINT MONO (105 1287);
FORCEPROP 1 LASTPIN (100 1125) $PN 2
J 0
(105 1135);
DISPLAY 0.617021 (105 1135);
PAINT MONO (105 1135);
FORCEPROP 2 LAST CDS_LIB pure_quanta
J 0
(100 1225);
DISPLAY INVISIBLE (100 1225);
FORCEPROP 1 LAST PATH I85
J 0
(150 1400);
DISPLAY 0.978723 (150 1400);
PAINT WHITE (150 1400);
DISPLAY INVISIBLE (150 1400);
FORCEPROP 1 LAST LOCATION R223
J 0
(150 1400);
DISPLAY 1.021277 (150 1400);
PAINT AQUA (150 1400);
DISPLAY INVISIBLE (150 1400);
FORCEPROP 0 LAST $SEC 1
J 0
(150 1400);
DISPLAY 0.680851 (150 1400);
PAINT MONO (150 1400);
DISPLAY INVISIBLE (150 1400);
FORCEPROP 0 LAST CDS_SEC 1
J 0
(150 1400);
DISPLAY 1.021277 (150 1400);
DISPLAY INVISIBLE (150 1400);
FORCEADD VCC15..1
(100 1475);
FORCEPROP 3 LASTPIN (100 1425) SIG_NAME P3V3_AUX\g
J 0
(110 1435);
DISPLAY 0.659574 (110 1435);
PAINT MONO (110 1435);
DISPLAY INVISIBLE (110 1435);
FORCEPROP 1 LAST HDL_POWER P3V3_AUX
J 1
(100 1525);
DISPLAY 0.617021 (100 1525);
PAINT GREEN (100 1525);
FORCEPROP 2 LAST CDS_LIB logical_power
J 0
(100 1475);
DISPLAY INVISIBLE (100 1475);
FORCEPROP 1 LAST PATH I86
J 0
(150 1500);
DISPLAY 0.872340 (150 1500);
PAINT AQUA (150 1500);
DISPLAY INVISIBLE (150 1500);
FORCEADD OFFPAGE..4
(1000 800);
FORCEPROP 2 LAST $XR0 251 
J 0
(1186 800);
DISPLAY 0.638298 (1186 800);
PAINT MONO (1186 800);
FORCEPROP 1 LAST COMMENT_BODY TRUE
J 0
(975 700);
DISPLAY 0.872340 (975 700);
PAINT GREEN (975 700);
DISPLAY INVISIBLE (975 700);
FORCEPROP 1 LAST OFFPAGE TRUE
J 0
(1325 675);
DISPLAY 0.872340 (1325 675);
PAINT GREEN (1325 675);
DISPLAY INVISIBLE (1325 675);
FORCEPROP 2 LAST CDS_LIB standard
J 0
(1000 800);
PAINT MONO (1000 800);
DISPLAY INVISIBLE (1000 800);
FORCEPROP 2 LAST PATH I87
J 0
(1200 850);
DISPLAY 1.021277 (1200 850);
DISPLAY INVISIBLE (1200 850);
FORCEADD OFFPAGE..2
(1025 950);
FORCEPROP 2 LAST $XR0 215 
J 0
(1214 950);
DISPLAY 0.638298 (1214 950);
PAINT MONO (1214 950);
FORCEPROP 1 LAST COMMENT_BODY TRUE
J 0
(980 855);
DISPLAY 0.872340 (980 855);
PAINT GREEN (980 855);
DISPLAY INVISIBLE (980 855);
FORCEPROP 1 LAST OFFPAGE TRUE
J 0
(1350 825);
DISPLAY 0.872340 (1350 825);
PAINT GREEN (1350 825);
DISPLAY INVISIBLE (1350 825);
FORCEPROP 2 LAST CDS_LIB standard
J 0
(1025 950);
DISPLAY INVISIBLE (1025 950);
FORCEPROP 2 LAST PATH I88
J 0
(1225 1000);
DISPLAY 1.021277 (1225 1000);
DISPLAY INVISIBLE (1225 1000);
FORCEADD UNIVERSAL_GND..1
(-175 1575);
FORCEPROP 3 LASTPIN (-175 1625) SIG_NAME GND\g
J 0
(-165 1635);
DISPLAY 0.659574 (-165 1635);
PAINT MONO (-165 1635);
DISPLAY INVISIBLE (-165 1635);
FORCEPROP 1 LAST HDL_POWER GND
J 1
(-150 1500);
DISPLAY 0.872340 (-150 1500);
PAINT GREEN (-150 1500);
DISPLAY INVISIBLE (-150 1500);
FORCEPROP 2 LAST CDS_LIB logical_power
J 0
(-175 1575);
DISPLAY INVISIBLE (-175 1575);
FORCEPROP 1 LAST PATH I89
J 0
(-100 1575);
DISPLAY 0.872340 (-100 1575);
PAINT AQUA (-100 1575);
DISPLAY INVISIBLE (-100 1575);
FORCEADD Q_RES..1
(-5400 100);
FORCEPROP 1 LAST PART_NUMBER CS04992FB07
J 0
(-5500 25);
DISPLAY 0.510638 (-5500 25);
PAINT BLUE (-5500 25);
DISPLAY INVISIBLE (-5500 25);
FORCEPROP 1 LAST MATERIAL CHIP
J 0
(-5200 150);
DISPLAY 0.617021 (-5200 150);
PAINT SKYBLUE (-5200 150);
FORCEPROP 1 LAST VALUE 49.9
J 2
(-5150 100);
DISPLAY 0.617021 (-5150 100);
PAINT SKYBLUE (-5150 100);
FORCEPROP 1 LAST TOLERANCE 1%
J 0
(-5275 150);
DISPLAY 0.617021 (-5275 150);
PAINT SKYBLUE (-5275 150);
FORCEPROP 1 LAST LOCATION PR1400
J 0
(-5625 100);
DISPLAY 0.617021 (-5625 100);
PAINT AQUA (-5625 100);
FORCEPROP 1 LASTPIN (-5500 100) $PN 1
J 0
(-5488 112);
DISPLAY 0.617021 (-5488 112);
FORCEPROP 1 LASTPIN (-5300 100) $PN 2
J 0
(-5338 112);
DISPLAY 0.617021 (-5338 112);
FORCEPROP 2 LAST CDS_LIB pure_quanta
J 0
(-5400 100);
PAINT MONO (-5400 100);
DISPLAY INVISIBLE (-5400 100);
FORCEPROP 1 LAST WATTAGE 1/16W
J 2
(-5200 -25);
DISPLAY 0.510638 (-5200 -25);
PAINT SKYBLUE (-5200 -25);
DISPLAY INVISIBLE (-5200 -25);
FORCEPROP 1 LAST PACK_TYPE 0402LF
J 0
(-5500 -25);
DISPLAY 0.510638 (-5500 -25);
PAINT SKYBLUE (-5500 -25);
DISPLAY INVISIBLE (-5500 -25);
FORCEPROP 1 LAST PATH I9
J 0
(-5450 250);
DISPLAY 0.978723 (-5450 250);
PAINT WHITE (-5450 250);
DISPLAY INVISIBLE (-5450 250);
FORCEPROP 2 LAST $SEC 1
J 0
(-5450 300);
DISPLAY 0.680851 (-5450 300);
PAINT MONO (-5450 300);
DISPLAY INVISIBLE (-5450 300);
FORCEPROP 2 LAST CDS_SEC 1
J 0
(-5450 300);
DISPLAY 1.021277 (-5450 300);
DISPLAY INVISIBLE (-5450 300);
FORCEADD UNIVERSAL_GND..1
(-175 2025);
FORCEPROP 3 LASTPIN (-175 2075) SIG_NAME GND\g
J 0
(-165 2085);
DISPLAY 0.659574 (-165 2085);
PAINT MONO (-165 2085);
DISPLAY INVISIBLE (-165 2085);
FORCEPROP 1 LAST HDL_POWER GND
J 1
(-150 1950);
DISPLAY 0.872340 (-150 1950);
PAINT GREEN (-150 1950);
DISPLAY INVISIBLE (-150 1950);
FORCEPROP 2 LAST CDS_LIB logical_power
J 0
(-175 2025);
DISPLAY INVISIBLE (-175 2025);
FORCEPROP 1 LAST PATH I90
J 0
(-100 2025);
DISPLAY 0.872340 (-100 2025);
PAINT AQUA (-100 2025);
DISPLAY INVISIBLE (-100 2025);
FORCEADD UNIVERSAL_GND..1
(-175 2475);
FORCEPROP 3 LASTPIN (-175 2525) SIG_NAME GND\g
J 0
(-165 2535);
DISPLAY 0.659574 (-165 2535);
PAINT MONO (-165 2535);
DISPLAY INVISIBLE (-165 2535);
FORCEPROP 1 LAST HDL_POWER GND
J 1
(-150 2400);
DISPLAY 0.872340 (-150 2400);
PAINT GREEN (-150 2400);
DISPLAY INVISIBLE (-150 2400);
FORCEPROP 2 LAST CDS_LIB logical_power
J 0
(-175 2475);
DISPLAY INVISIBLE (-175 2475);
FORCEPROP 1 LAST PATH I91
J 0
(-100 2475);
DISPLAY 0.872340 (-100 2475);
PAINT AQUA (-100 2475);
DISPLAY INVISIBLE (-100 2475);
FORCEADD UNIVERSAL_GND..1
(-175 2925);
FORCEPROP 3 LASTPIN (-175 2975) SIG_NAME GND\g
J 0
(-165 2985);
DISPLAY 0.659574 (-165 2985);
PAINT MONO (-165 2985);
DISPLAY INVISIBLE (-165 2985);
FORCEPROP 1 LAST HDL_POWER GND
J 1
(-150 2850);
DISPLAY 0.872340 (-150 2850);
PAINT GREEN (-150 2850);
DISPLAY INVISIBLE (-150 2850);
FORCEPROP 2 LAST CDS_LIB logical_power
J 0
(-175 2925);
DISPLAY INVISIBLE (-175 2925);
FORCEPROP 1 LAST PATH I92
J 0
(-100 2925);
DISPLAY 0.872340 (-100 2925);
PAINT AQUA (-100 2925);
DISPLAY INVISIBLE (-100 2925);
FORCEADD UNIVERSAL_GND..1
(-175 3375);
FORCEPROP 3 LASTPIN (-175 3425) SIG_NAME GND\g
J 0
(-165 3435);
DISPLAY 0.659574 (-165 3435);
PAINT MONO (-165 3435);
DISPLAY INVISIBLE (-165 3435);
FORCEPROP 1 LAST HDL_POWER GND
J 1
(-150 3300);
DISPLAY 0.872340 (-150 3300);
PAINT GREEN (-150 3300);
DISPLAY INVISIBLE (-150 3300);
FORCEPROP 2 LAST CDS_LIB logical_power
J 0
(-175 3375);
DISPLAY INVISIBLE (-175 3375);
FORCEPROP 1 LAST PATH I93
J 0
(-100 3375);
DISPLAY 0.872340 (-100 3375);
PAINT AQUA (-100 3375);
DISPLAY INVISIBLE (-100 3375);
FORCEADD UNIVERSAL_GND..1
(-175 3825);
FORCEPROP 3 LASTPIN (-175 3875) SIG_NAME GND\g
J 0
(-165 3885);
DISPLAY 0.659574 (-165 3885);
PAINT MONO (-165 3885);
DISPLAY INVISIBLE (-165 3885);
FORCEPROP 1 LAST HDL_POWER GND
J 1
(-150 3750);
DISPLAY 0.872340 (-150 3750);
PAINT GREEN (-150 3750);
DISPLAY INVISIBLE (-150 3750);
FORCEPROP 2 LAST CDS_LIB logical_power
J 0
(-175 3825);
DISPLAY INVISIBLE (-175 3825);
FORCEPROP 1 LAST PATH I94
J 0
(-100 3825);
DISPLAY 0.872340 (-100 3825);
PAINT AQUA (-100 3825);
DISPLAY INVISIBLE (-100 3825);
FORCEADD Q_RES..1
(-6200 225);
FORCEPROP 1 LAST PART_NUMBER CS32432FB03
J 0
(-6250 250);
DISPLAY 0.638298 (-6250 250);
DISPLAY INVISIBLE (-6250 250);
FORCEPROP 1 LAST TOLERANCE 1%
J 0
(-5900 225);
DISPLAY 0.638298 (-5900 225);
FORCEPROP 1 LAST VALUE 24.3K
J 2
(-5925 225);
DISPLAY 0.638298 (-5925 225);
FORCEPROP 1 LAST WATTAGE 1/16W
J 2
(-5675 225);
DISPLAY 0.638298 (-5675 225);
FORCEPROP 1 LAST MATERIAL CHIP
J 0
(-5625 225);
DISPLAY 0.638298 (-5625 225);
FORCEPROP 1 LAST LOCATION PR203
J 0
(-6375 250);
DISPLAY 0.638298 (-6375 250);
FORCEPROP 1 LASTPIN (-6300 225) $PN 1
J 0
(-6288 237);
DISPLAY 0.787234 (-6288 237);
PAINT MONO (-6288 237);
FORCEPROP 1 LASTPIN (-6100 225) $PN 2
J 0
(-6138 237);
DISPLAY 0.787234 (-6138 237);
PAINT MONO (-6138 237);
FORCEPROP 1 LAST PATH I95
J 0
(-6250 375);
DISPLAY 0.978723 (-6250 375);
PAINT WHITE (-6250 375);
DISPLAY INVISIBLE (-6250 375);
FORCEPROP 2 LAST CDS_LIB pure_quanta
J 0
(-6200 225);
DISPLAY INVISIBLE (-6200 225);
FORCEPROP 1 LAST PACK_TYPE 0402LF
J 0
(-5950 75);
DISPLAY 0.638298 (-5950 75);
DISPLAY INVISIBLE (-5950 75);
FORCEPROP 0 LAST $SEC 1
J 0
(-6250 300);
DISPLAY 0.680851 (-6250 300);
PAINT MONO (-6250 300);
DISPLAY INVISIBLE (-6250 300);
FORCEPROP 0 LAST CDS_SEC 1
J 0
(-6250 300);
DISPLAY 1.021277 (-6250 300);
DISPLAY INVISIBLE (-6250 300);
FORCEADD Q_CAP..1
(-2050 5250);
FORCEPROP 1 LAST PART_NUMBER CH4104K1B00
J 0
(-2000 5175);
DISPLAY 0.638298 (-2000 5175);
DISPLAY INVISIBLE (-2000 5175);
FORCEPROP 1 LAST TOLERANCE 10%
J 0
(-2000 5225);
DISPLAY 0.638298 (-2000 5225);
FORCEPROP 1 LAST VALUE 0.1UF
J 0
(-2000 5325);
DISPLAY 0.638298 (-2000 5325);
FORCEPROP 1 LAST VOLTAGE 25V
J 0
(-2000 5275);
DISPLAY 0.638298 (-2000 5275);
FORCEPROP 1 LAST PACK_TYPE 0402
J 0
(-2000 5125);
DISPLAY 0.638298 (-2000 5125);
FORCEPROP 1 LAST MATERIAL EMPTY
J 0
(-2000 5200);
DISPLAY 0.638298 (-2000 5200);
PAINT RED (-2000 5200);
FORCEPROP 1 LAST LOCATION PC2368
J 0
(-2000 5350);
DISPLAY 0.978723 (-2000 5350);
FORCEPROP 1 LASTPIN (-2050 5350) $PN 1
J 0
(-2040 5330);
DISPLAY 0.787234 (-2040 5330);
PAINT MONO (-2040 5330);
FORCEPROP 1 LASTPIN (-2050 5150) $PN 2
J 0
(-2040 5130);
DISPLAY 0.787234 (-2040 5130);
PAINT MONO (-2040 5130);
FORCEPROP 1 LAST PATH I96
J 0
(-2000 5400);
DISPLAY 0.978723 (-2000 5400);
PAINT WHITE (-2000 5400);
DISPLAY INVISIBLE (-2000 5400);
FORCEPROP 2 LAST CDS_LIB pure_quanta
J 0
(-2050 5250);
DISPLAY INVISIBLE (-2050 5250);
FORCEPROP 0 LAST $SEC 1
J 0
(-2000 5400);
DISPLAY 0.680851 (-2000 5400);
PAINT MONO (-2000 5400);
DISPLAY INVISIBLE (-2000 5400);
FORCEPROP 0 LAST CDS_SEC 1
J 0
(-2000 5400);
DISPLAY 1.021277 (-2000 5400);
DISPLAY INVISIBLE (-2000 5400);
FORCEADD QUANTA_TITLE_BLOCK_C..1
(1500 -725);
FORCEPROP 0 LAST CDS_CON_LAST_MODIFIED Fri Aug 25 14:05:07 2023
J 0
(-385 -710);
DISPLAY INVISIBLE (-385 -710);
FORCEPROP 1 LAST CUSTOM_TXT_CDS <CON_LAST_MODIFIED>
J 0
(-385 -710);
DISPLAY 0.978723 (-385 -710);
FORCEPROP 2 LAST CUSTOM_TXT_CDS <XR_PAGE_TITLE>
J 0
(-6390 4525);
DISPLAY 0.638298 (-6390 4525);
PAINT PINK (-6390 4525);
DISPLAY INVISIBLE (-6390 4525);
FORCEPROP 1 LAST CUSTOM_TXT_CDS <NAME_2>
J 0
(-1675 -675);
FORCEPROP 1 LAST CUSTOM_TXT_CDS <NAME_1>
J 0
(-1675 -550);
FORCEPROP 1 LAST CUSTOM_TXT_CDS <Q_NUMBER>
J 0
(97 -622);
DISPLAY 1.212766 (97 -622);
FORCEPROP 1 LAST CUSTOM_TXT_CDS <Q_PROJ>
J 0
(-882 -623);
DISPLAY 1.212766 (-882 -623);
FORCEPROP 1 LAST CUSTOM_TXT_CDS <Q_REV>
J 0
(1316 -622);
DISPLAY 1.212766 (1316 -622);
FORCEPROP 1 LAST CUSTOM_TXT_CDS <CON_PAGE_NUM> OF <CON_TOTAL_PAGES>
J 0
(1054 -707);
DISPLAY 0.978723 (1054 -707);
FORCEPROP 1 LAST Q_TITLE VCCD_HV CPU1 VR CONTROLLER (1/2)
J 0
(-7800 -675);
DISPLAY 2.446809 (-7800 -675);
PAINT GREEN (-7800 -675);
FORCEPROP 1 LAST Q_DEPT 
J 1
(-2263 -676);
DISPLAY 1.957447 (-2263 -676);
PAINT GREEN (-2263 -676);
FORCEPROP 2 LAST CDS_XR_PAGE_TITLE CR-296 : @S9S_MB_2U_LIB.S9S_MB_2U(SCH_1):PAGE296
J 0
(-6390 4525);
DISPLAY 0.638298 (-6390 4525);
PAINT PINK (-6390 4525);
DISPLAY INVISIBLE (-6390 4525);
FORCEPROP 2 LAST CDS_LIB pure_quanta
J 0
(1500 -725);
DISPLAY INVISIBLE (1500 -725);
FORCEPROP 1 LAST CDS_LMAN_SYM_OUTLINE -9475,6775,100,-125
J 0
(1500 -725);
DISPLAY 0.468085 (1500 -725);
PAINT GREEN (1500 -725);
DISPLAY INVISIBLE (1500 -725);
FORCEPROP 2 LAST PAGE_BORDER TRUE
J 0
(-6390 4525);
DISPLAY 0.638298 (-6390 4525);
PAINT PINK (-6390 4525);
DISPLAY INVISIBLE (-6390 4525);
FORCEPROP 1 LAST COMMENT_BODY TRUE
J 0
(1512 -738);
DISPLAY 0.978723 (1512 -738);
PAINT GREEN (1512 -738);
DISPLAY INVISIBLE (1512 -738);
FORCEADD DNS..2
(-6175 350);
PAINT RED (-6175 350);
FORCEPROP 1 LAST COMMENT_BODY TRUE
R 1
J 0
(-6100 125);
DISPLAY 0.872340 (-6100 125);
PAINT GREEN (-6100 125);
DISPLAY INVISIBLE (-6100 125);
FORCEPROP 2 LAST CDS_LIB mstr_misc
J 0
(-6175 350);
PAINT MONO (-6175 350);
DISPLAY INVISIBLE (-6175 350);
FORCEADD DNS..1
(-5000 -225);
PAINT RED (-5000 -225);
FORCEPROP 1 LAST COMMENT_BODY TRUE
R 1
J 0
(-4925 -450);
DISPLAY 0.872340 (-4925 -450);
PAINT GREEN (-4925 -450);
DISPLAY INVISIBLE (-4925 -450);
FORCEPROP 2 LAST CDS_LIB mstr_misc
J 0
(-5000 -225);
DISPLAY INVISIBLE (-5000 -225);
FORCEADD DNS..1
(-4475 5625);
PAINT RED (-4475 5625);
FORCEPROP 1 LAST COMMENT_BODY TRUE
R 1
J 0
(-4400 5400);
DISPLAY 0.872340 (-4400 5400);
PAINT GREEN (-4400 5400);
DISPLAY INVISIBLE (-4400 5400);
FORCEPROP 2 LAST CDS_LIB mstr_misc
J 0
(-4475 5625);
DISPLAY INVISIBLE (-4475 5625);
FORCEADD DNS..1
(-4150 -225);
PAINT RED (-4150 -225);
FORCEPROP 1 LAST COMMENT_BODY TRUE
R 1
J 0
(-4075 -450);
DISPLAY 0.872340 (-4075 -450);
PAINT GREEN (-4075 -450);
DISPLAY INVISIBLE (-4075 -450);
FORCEPROP 2 LAST CDS_LIB mstr_misc
J 0
(-4150 -225);
DISPLAY INVISIBLE (-4150 -225);
FORCEADD DNS..1
(-450 800);
PAINT RED (-450 800);
FORCEPROP 1 LAST COMMENT_BODY TRUE
R 1
J 0
(-375 575);
DISPLAY 0.872340 (-375 575);
PAINT GREEN (-375 575);
DISPLAY INVISIBLE (-375 575);
FORCEPROP 2 LAST CDS_LIB mstr_misc
J 0
(-450 800);
DISPLAY INVISIBLE (-450 800);
FORCEADD DNS..1
(-1675 5250);
PAINT RED (-1675 5250);
FORCEPROP 1 LAST COMMENT_BODY TRUE
R 1
J 0
(-1600 5025);
DISPLAY 0.872340 (-1600 5025);
PAINT GREEN (-1600 5025);
DISPLAY INVISIBLE (-1600 5025);
FORCEPROP 2 LAST CDS_LIB mstr_misc
J 0
(-1675 5250);
DISPLAY INVISIBLE (-1675 5250);
FORCEADD DNS..1
(-100 50);
PAINT RED (-100 50);
FORCEPROP 1 LAST COMMENT_BODY TRUE
R 1
J 0
(-25 -175);
DISPLAY 0.872340 (-25 -175);
PAINT GREEN (-25 -175);
DISPLAY INVISIBLE (-25 -175);
FORCEPROP 2 LAST CDS_LIB mstr_misc
J 0
(-100 50);
DISPLAY INVISIBLE (-100 50);
FORCEADD DNS..1
(-2025 5250);
PAINT RED (-2025 5250);
FORCEPROP 2 LAST CDS_LIB mstr_misc
J 0
(-2025 5250);
DISPLAY INVISIBLE (-2025 5250);
FORCEPROP 1 LAST COMMENT_BODY TRUE
R 1
J 0
(-1950 5025);
DISPLAY 0.872340 (-1950 5025);
PAINT GREEN (-1950 5025);
DISPLAY INVISIBLE (-1950 5025);
WIRE 16 -1 (100 1425)(100 1325);
WIRE 16 -1 (-5075 2050)(-5075 2000);
WIRE 16 -1 (-7550 5350)(-7550 5400);
WIRE 16 -1 (-7325 5350)(-7550 5350);
WIRE 16 -1 (-7550 5275)(-7550 5350);
WIRE 16 -1 (-5450 3700)(-5450 3600);
WIRE 16 -1 (-5750 5600)(-5750 5650);
WIRE 16 -1 (-5750 5600)(-5425 5600);
WIRE 16 -1 (-500 5525)(-500 5450);
WIRE 16 -1 (-6850 225)(-6850 200);
WIRE 16 -1 (-6850 225)(-6300 225);
WIRE 16 -1 (-4875 -400)(-4875 -450);
WIRE 16 -1 (-5000 -400)(-4875 -400);
WIRE 16 -1 (-4875 -300)(-4875 -400);
WIRE 16 -1 (-5450 2925)(-5450 2875);
WIRE 16 -1 (-5450 2925)(-5875 2925);
WIRE 16 -1 (-7550 4950)(-7550 4875);
WIRE 16 -1 (-7325 4950)(-7550 4950);
WIRE 16 -1 (-7550 5075)(-7550 4950);
WIRE 16 -1 (-4025 -400)(-4025 -450);
WIRE 16 -1 (-4150 -400)(-4025 -400);
WIRE 16 -1 (-4025 -300)(-4025 -400);
WIRE 16 -1 (-3725 -175)(-3725 -100);
WIRE 16 -1 (-3775 1050)(-3775 975);
WIRE 16 -1 (-3775 1050)(-3625 1050);
WIRE 16 -1 (-3825 1900)(-3825 2050);
WIRE 16 -1 (-1325 -125)(-1325 -50);
WIRE 16 -1 (-4375 5600)(-3825 5600);
WIRE 16 -1 (-900 4575)(-1300 4575);
WIRE 16 -1 (-900 5050)(-1300 5050);
WIRE 16 -1 (-175 -150)(-175 -50);
WIRE 16 -1 (250 550)(250 475);
WIRE 16 -1 (-375 550)(250 550);
WIRE 16 -1 (-175 1200)(-175 1175);
WIRE 16 -1 (-700 1200)(-175 1200);
WIRE 16 -1 (-175 1650)(-175 1625);
WIRE 16 -1 (-700 1650)(-175 1650);
WIRE 16 -1 (-175 2100)(-175 2075);
WIRE 16 -1 (-700 2100)(-175 2100);
WIRE 16 -1 (-175 2550)(-175 2525);
WIRE 16 -1 (-700 2550)(-175 2550);
WIRE 16 -1 (-175 3000)(-175 2975);
WIRE 16 -1 (-700 3000)(-175 3000);
WIRE 16 -1 (-175 3450)(-175 3425);
WIRE 16 -1 (-700 3450)(-175 3450);
WIRE 16 -1 (-175 3900)(-175 3875);
WIRE 16 -1 (-700 3900)(-175 3900);
WIRE 16 -1 (-1300 4575)(-1300 4675);
WIRE 16 -1 (-1700 4575)(-1300 4575);
WIRE 16 -1 (-1700 4675)(-1700 4575);
WIRE 16 -1 (-1050 4000)(-2275 4000);
FORCEPROP 2 LAST SIG_NAME NC_PVCCD_HV_CPU1_APWM2
J 0
(-2110 4010);
DISPLAY 0.617021 (-2110 4010);
WIRE 16 -1 (-5225 4300)(-3625 4300);
FORCEPROP 2 LAST SIG_NAME SMB_CLK_PVCCD_HV_CPU1
J 0
(-4660 4310);
DISPLAY 0.617021 (-4660 4310);
WIRE 16 -1 (-5225 4850)(-3625 4850);
FORCEPROP 2 LAST SIG_NAME SVID_DIO_PVCCD_HV_CPU1_R
J 0
(-4685 4860);
DISPLAY 0.617021 (-4685 4860);
WIRE 16 -1 (-5225 4700)(-3625 4700);
FORCEPROP 2 LAST SIG_NAME SVID_ALERT_PVCCD_HV_CPU1_R
J 0
(-4685 4710);
DISPLAY 0.617021 (-4685 4710);
WIRE 16 -1 (-4775 650)(-3625 650);
FORCEPROP 2 LAST SIG_NAME NC_PVCCD_HV_CPU1_BVR_RDY
J 0
(-4710 660);
DISPLAY 0.617021 (-4710 660);
WIRE 16 -1 (-5225 5000)(-3625 5000);
FORCEPROP 2 LAST SIG_NAME SVID_CLK_PVCCD_HV_CPU1_R
J 0
(-4685 5010);
DISPLAY 0.617021 (-4685 5010);
WIRE 16 -1 (-5225 4000)(-3625 4000);
FORCEPROP 2 LAST SIG_NAME NC_PVCCD_HV_CPU1_SMB_ALERT
J 0
(-4810 4010);
DISPLAY 0.617021 (-4810 4010);
WIRE 16 -1 (-5225 5300)(-3625 5300);
FORCEPROP 2 LAST SIG_NAME PVCCD_HV_CPU1_EN_R
J 0
(-4660 5310);
DISPLAY 0.617021 (-4660 5310);
WIRE 16 -1 (-3825 3150)(-3625 3150);
WIRE 16 -1 (-3825 3075)(-3825 3150);
WIRE 16 -1 (-4475 3175)(-4475 3075);
WIRE 16 -1 (-3825 3075)(-4475 3075);
WIRE 16 -1 (-7150 3075)(-6250 3075);
FORCEPROP 2 LAST SIG_NAME VSENSE_PVCCD_HV_CPU1_DN
J 0
(-7060 3085);
DISPLAY 0.617021 (-7060 3085);
WIRE 16 -1 (-6250 3075)(-4475 3075);
WIRE 16 -1 (-6250 2925)(-6250 3075);
WIRE 16 -1 (-6250 2925)(-6075 2925);
WIRE 16 -1 (-5225 4150)(-3625 4150);
FORCEPROP 2 LAST SIG_NAME SMB_DIO_PVCCD_HV_CPU1
J 0
(-4660 4160);
DISPLAY 0.617021 (-4660 4160);
WIRE 16 -1 (-3625 3400)(-3825 3400);
WIRE 16 -1 (-3825 3450)(-3825 3400);
WIRE 16 -1 (-4475 3375)(-4475 3450);
WIRE 16 -1 (-3825 3450)(-4475 3450);
FORCEPROP 2 LAST SIG_NAME SH_PVCCD_HV_CPU1_R
J 0
(-4460 3460);
DISPLAY 0.617021 (-4460 3460);
WIRE 16 -1 (-4825 3450)(-4475 3450);
WIRE 16 -1 (-4800 5450)(-5225 5450);
WIRE 16 -1 (-4800 5450)(-3625 5450);
FORCEPROP 2 LAST SIG_NAME PWRGD_PVCCD_HV_CPU1_R
J 0
(-4660 5460);
DISPLAY 0.617021 (-4660 5460);
WIRE 16 -1 (-4800 5600)(-5225 5600);
WIRE 16 -1 (-4800 5450)(-4800 5600);
WIRE 16 -1 (-4575 5600)(-4800 5600);
WIRE 16 -1 (-4025 50)(-3975 50);
WIRE 16 -1 (-3975 50)(-3975 100);
WIRE 16 -1 (-3975 100)(-3625 100);
WIRE 16 -1 (-4875 -100)(-4875 100);
WIRE 16 -1 (-4875 100)(-3975 100);
WIRE 16 -1 (-5300 100)(-5000 100);
WIRE 16 -1 (-4875 100)(-5000 100);
FORCEPROP 2 LAST SIG_NAME PVCCD_HV_CPU1_ISENSE_P
J 0
(-5085 110);
DISPLAY 0.617021 (-5085 110);
WIRE 16 -1 (-5000 -100)(-5000 100);
WIRE 16 -1 (-4025 0)(-3625 0);
WIRE 16 -1 (-4025 -100)(-4025 0);
WIRE 16 -1 (-4025 0)(-4150 0);
WIRE 16 -1 (-4150 -100)(-4150 0);
WIRE 16 -1 (-4275 0)(-4150 0);
WIRE 16 -1 (-5300 0)(-4275 0);
FORCEPROP 2 LAST SIG_NAME PVCCD_HV_CPU1_ISENSE_N
J 0
(-5085 10);
DISPLAY 0.617021 (-5085 10);
WIRE 16 -1 (-4275 50)(-4275 0);
WIRE 16 -1 (-4225 50)(-4275 50);
WIRE 16 -1 (-5075 1650)(-5075 1200);
WIRE 16 -1 (-5075 1200)(-3625 1200);
FORCEPROP 2 LAST SIG_NAME PVCCD_HV_CPU1_PIN_ALT
J 0
(-4710 1210);
DISPLAY 0.617021 (-4710 1210);
WIRE 16 -1 (-5175 1200)(-5075 1200);
WIRE 16 -1 (-3825 2300)(-3625 2300);
WIRE 16 -1 (-3625 2050)(-3825 2050);
WIRE 16 -1 (-3825 2050)(-3825 2300);
WIRE 16 -1 (-4750 1450)(-3625 1450);
FORCEPROP 2 LAST SIG_NAME PVCCD_HV_CPU1_FAULT
J 0
(-4710 1460);
DISPLAY 0.617021 (-4710 1460);
WIRE 16 -1 (-4750 1650)(-4750 1450);
WIRE 16 -1 (-3725 -100)(-3625 -100);
WIRE 16 -1 (-6100 350)(-5700 350);
WIRE 16 -1 (-5700 350)(-3625 350);
FORCEPROP 2 LAST SIG_NAME PVCCD_HV_CPU1_ADDR
J 0
(-4710 360);
DISPLAY 0.617021 (-4710 360);
WIRE 16 -1 (-5700 225)(-5700 350);
WIRE 16 -1 (-6100 225)(-5700 225);
WIRE 16 -1 (-2275 1200)(-900 1200);
FORCEPROP 2 LAST SIG_NAME NC_PVCCD_HV_CPU1_ACSP8
J 0
(-2110 1210);
DISPLAY 0.617021 (-2110 1210);
WIRE 16 -1 (-2275 1300)(-1050 1300);
FORCEPROP 2 LAST SIG_NAME NC_PVCCD_HV_CPU1_APWM8
J 0
(-2110 1310);
DISPLAY 0.617021 (-2110 1310);
WIRE 16 -1 (-175 150)(-175 250);
WIRE 16 -1 (500 250)(-175 250);
WIRE 16 -1 (-1325 250)(-1325 150);
WIRE 16 -1 (-175 250)(-1325 250);
FORCEPROP 2 LAST SIG_NAME PVCCD_HV_CPU1_ATSEN
J 0
(-360 260);
DISPLAY 0.617021 (-360 260);
WIRE 16 -1 (-2275 250)(-1325 250);
WIRE 16 -1 (-2275 2100)(-900 2100);
FORCEPROP 2 LAST SIG_NAME NC_PVCCD_HV_CPU1_ACSP6
J 0
(-2110 2110);
DISPLAY 0.617021 (-2110 2110);
WIRE 16 -1 (-2275 2200)(-1050 2200);
FORCEPROP 2 LAST SIG_NAME NC_PVCCD_HV_CPU1_APWM6
J 0
(-2110 2210);
DISPLAY 0.617021 (-2110 2210);
WIRE 16 -1 (-2275 2550)(-900 2550);
FORCEPROP 2 LAST SIG_NAME NC_PVCCD_HV_CPU1_ACSP5
J 0
(-2110 2560);
DISPLAY 0.617021 (-2110 2560);
WIRE 16 -1 (-2275 2650)(-1050 2650);
FORCEPROP 2 LAST SIG_NAME NC_PVCCD_HV_CPU1_APWM5
J 0
(-2110 2660);
DISPLAY 0.617021 (-2110 2660);
WIRE 16 -1 (-2275 4450)(-1050 4450);
FORCEPROP 2 LAST SIG_NAME PVCCD_HV_CPU1_APWM1
J 0
(-2110 4460);
DISPLAY 0.617021 (-2110 4460);
WIRE 16 -1 (-2275 1650)(-900 1650);
FORCEPROP 2 LAST SIG_NAME NC_PVCCD_HV_CPU1_ACSP7
J 0
(-2110 1660);
DISPLAY 0.617021 (-2110 1660);
WIRE 16 -1 (-2275 550)(-900 550);
FORCEPROP 2 LAST SIG_NAME PVCCD_HV_CPU1_ISYS_R
J 0
(-1960 560);
DISPLAY 0.617021 (-1960 560);
WIRE 16 -1 (-900 550)(-575 550);
WIRE 16 -1 (-900 550)(-900 800);
WIRE 16 -1 (-575 800)(-900 800);
WIRE 16 -1 (-1300 4875)(-1300 4975);
WIRE 16 -1 (-900 4975)(-1300 4975);
WIRE 16 -1 (-1700 4875)(-1700 4975);
WIRE 16 -1 (-1300 4975)(-1700 4975);
WIRE 16 -1 (-1700 4975)(-2125 4975);
FORCEPROP 2 LAST SIG_NAME PVCCD_HV_CPU1_VREF
J 0
(-2085 4985);
DISPLAY 0.617021 (-2085 4985);
WIRE 16 -1 (-2125 5150)(-2125 4975);
WIRE 16 -1 (-2275 5150)(-2125 5150);
WIRE 16 -1 (-2275 1750)(-1050 1750);
FORCEPROP 2 LAST SIG_NAME NC_PVCCD_HV_CPU1_APWM7
J 0
(-2110 1760);
DISPLAY 0.617021 (-2110 1760);
WIRE 16 -1 (-1050 3550)(-2275 3550);
FORCEPROP 2 LAST SIG_NAME NC_PVCCD_HV_CPU1_APWM3
J 0
(-2110 3560);
DISPLAY 0.617021 (-2110 3560);
WIRE 16 -1 (-1050 3100)(-2275 3100);
FORCEPROP 2 LAST SIG_NAME NC_PVCCD_HV_CPU1_APWM4
J 0
(-2110 3110);
DISPLAY 0.617021 (-2110 3110);
WIRE 16 -1 (-2275 3000)(-900 3000);
FORCEPROP 2 LAST SIG_NAME NC_PVCCD_HV_CPU1_ACSP4
J 0
(-2110 3010);
DISPLAY 0.617021 (-2110 3010);
WIRE 16 -1 (-2275 3450)(-900 3450);
FORCEPROP 2 LAST SIG_NAME NC_PVCCD_HV_CPU1_ACSP3
J 0
(-2110 3460);
DISPLAY 0.617021 (-2110 3460);
WIRE 16 -1 (-900 950)(-2275 950);
FORCEPROP 2 LAST SIG_NAME IRQ_PVCCD_CPU1_VRHOT_LVC3_R_N
J 0
(-2110 960);
DISPLAY 0.638298 (-2110 960);
WIRE 16 -1 (-2275 3900)(-900 3900);
FORCEPROP 2 LAST SIG_NAME NC_PVCCD_HV_CPU1_ACSP2
J 0
(-2110 3910);
DISPLAY 0.617021 (-2110 3910);
WIRE 16 -1 (-2050 5350)(-2050 5450);
WIRE 16 -1 (-2275 5450)(-2050 5450);
FORCEPROP 2 LAST SIG_NAME PVCCD_HV_CPU1_VCC
J 0
(-2085 5460);
DISPLAY 0.617021 (-2085 5460);
WIRE 16 -1 (-2050 5450)(-1700 5450);
WIRE 16 -1 (-1700 5350)(-1700 5450);
WIRE 16 -1 (-1700 5450)(-1300 5450);
WIRE 16 -1 (-1075 5450)(-1300 5450);
WIRE 16 -1 (-1300 5350)(-1300 5450);
WIRE 16 -1 (-1050 4350)(-2275 4350);
FORCEPROP 2 LAST SIG_NAME PVCCD_HV_CPU1_ACSP1
J 0
(-2110 4360);
DISPLAY 0.617021 (-2110 4360);
WIRE 17 273 (-150 5875)(1421 5875);
WIRE 17 273 (1421 5875)(1421 4400);
WIRE 17 273 (-150 5875)(-150 4400);
WIRE 17 273 (-150 4400)(1421 4400);
WIRE 16 -1 (-2050 5150)(-2050 5050);
WIRE 16 -1 (-2050 5050)(-1700 5050);
WIRE 16 -1 (-1700 5150)(-1700 5050);
WIRE 16 -1 (-1700 5050)(-1300 5050);
WIRE 16 -1 (-1300 5150)(-1300 5050);
WIRE 16 -1 (-5000 -300)(-5000 -400);
WIRE 16 -1 (-4750 2000)(-4750 1850);
WIRE 16 -1 (-4750 2000)(-5075 2000);
WIRE 16 -1 (-5075 1850)(-5075 2000);
WIRE 16 -1 (-7325 5075)(-7325 4950);
WIRE 16 -1 (-7325 5350)(-7325 5275);
WIRE 16 -1 (-7075 5350)(-7325 5350);
WIRE 16 -1 (-7075 5075)(-6900 5075);
WIRE 16 -1 (-7075 5175)(-7075 5075);
WIRE 16 -1 (-7075 5350)(-7075 5175);
WIRE 16 -1 (-7075 5175)(-6900 5175);
WIRE 16 -1 (-5450 3600)(-5850 3600);
WIRE 16 -1 (-4150 -300)(-4150 -400);
WIRE 16 -1 (-500 5450)(-875 5450);
WIRE 16 -1 (-5425 4150)(-6625 4150);
FORCEPROP 2 LAST SIG_NAME SMB_VR_3V3AUX_SDA_R
J 0
(-6560 4160);
DISPLAY 0.617021 (-6560 4160);
WIRE 16 -1 (-7250 350)(-6300 350);
FORCEPROP 2 LAST SIG_NAME PVCCD_HV_CPU1_VREF
J 0
(-7185 360);
DISPLAY 0.617021 (-7185 360);
WIRE 16 -1 (-5500 100)(-6750 100);
FORCEPROP 2 LAST SIG_NAME P12V_AUX_CPU1_DIMM_ISEN_P
J 0
(-6610 110);
DISPLAY 0.617021 (-6610 110);
WIRE 16 -1 (-6325 4700)(-5425 4700);
FORCEPROP 2 LAST SIG_NAME SVID_ALERT1_CPU1_R_N
J 0
(-6185 4710);
DISPLAY 0.617021 (-6185 4710);
WIRE 16 -1 (-375 800)(950 800);
FORCEPROP 0 LAST SIG_NAME PVCCD_HV_CPU1_NVDIMM_ISENSE
J 0
(190 810);
DISPLAY 0.617021 (190 810);
WIRE 16 -1 (-700 950)(100 950);
WIRE 16 -1 (100 1125)(100 950);
WIRE 16 -1 (975 950)(100 950);
FORCEPROP 2 LAST SIG_NAME IRQ_PVCCD_CPU1_VRHOT_LVC3_N
J 0
(190 960);
DISPLAY 0.617021 (190 960);
WIRE 16 -1 (-6325 5450)(-5425 5450);
FORCEPROP 2 LAST SIG_NAME PWRGD_PVCCD_HV_CPU1
J 0
(-6260 5460);
DISPLAY 0.617021 (-6260 5460);
WIRE 16 -1 (-6325 5300)(-5425 5300);
FORCEPROP 2 LAST SIG_NAME FM_PVCCD_HV_CPU1_EN
J 0
(-6260 5310);
DISPLAY 0.617021 (-6260 5310);
WIRE 16 -1 (-6150 5175)(-6700 5175);
WIRE 16 -1 (-6150 5000)(-6150 5175);
WIRE 16 -1 (-6150 5000)(-5425 5000);
FORCEPROP 2 LAST SIG_NAME SVID_CLK1_CPU1_R
J 0
(-6085 5010);
DISPLAY 0.617021 (-6085 5010);
WIRE 16 -1 (-6325 5000)(-6150 5000);
WIRE 16 -1 (-6700 5075)(-6200 5075);
WIRE 16 -1 (-6200 5075)(-6200 4850);
WIRE 16 -1 (-5425 4850)(-6200 4850);
FORCEPROP 2 LAST SIG_NAME SVID_DIO1_CPU1_R
J 0
(-6085 4860);
DISPLAY 0.617021 (-6085 4860);
WIRE 16 -1 (-6325 4850)(-6200 4850);
WIRE 16 -1 (-6625 4300)(-5425 4300);
FORCEPROP 2 LAST SIG_NAME SMB_VR_3V3AUX_SCL_R
J 0
(-6560 4310);
DISPLAY 0.617021 (-6560 4310);
WIRE 17 273 (-7425 3550)(-7100 3550);
WIRE 17 273 (-7100 3550)(-7100 3000);
WIRE 17 273 (-7425 3000)(-7425 3550);
WIRE 17 273 (-7425 3000)(-7100 3000);
WIRE 16 -1 (-6250 3600)(-6050 3600);
WIRE 16 -1 (-6150 3450)(-6250 3450);
WIRE 16 -1 (-6250 3450)(-6250 3600);
WIRE 16 -1 (-7150 3450)(-6250 3450);
FORCEPROP 2 LAST SIG_NAME VSENSE_PVCCD_HV_CPU1_DP
J 0
(-7060 3460);
DISPLAY 0.617021 (-7060 3460);
WIRE 16 -1 (-5900 3450)(-5025 3450);
FORCEPROP 2 LAST SIG_NAME SH_PVCCD_HV_CPU1
J 0
(-5785 3460);
DISPLAY 0.617021 (-5785 3460);
WIRE 16 -1 (-5500 0)(-6750 0);
FORCEPROP 2 LAST SIG_NAME P12V_AUX_CPU1_DIMM_ISEN_N
J 0
(-6610 10);
DISPLAY 0.617021 (-6610 10);
WIRE 17 273 (-7700 -325)(-5900 -325);
WIRE 17 273 (-5900 -325)(-5900 -550);
WIRE 17 273 (-7700 -325)(-7700 -550);
WIRE 17 273 (-7700 -550)(-5900 -550);
DOT 1 (-1700 5050);
DOT 1 (-2050 5450);
DOT 1 (100 950);
DOT 1 (-175 250);
DOT 1 (-1300 5450);
DOT 1 (-1300 5050);
DOT 1 (-1300 4975);
DOT 1 (-1300 4575);
DOT 1 (-1700 5450);
DOT 1 (-1700 4975);
DOT 1 (-900 550);
DOT 1 (-1325 250);
DOT 1 (-3825 2050);
DOT 1 (-3975 100);
DOT 1 (-4025 0);
DOT 1 (-4150 0);
DOT 1 (-4275 0);
DOT 1 (-4025 -400);
DOT 1 (-4800 5600);
DOT 1 (-4800 5450);
DOT 1 (-6150 5000);
DOT 1 (-6200 4850);
DOT 1 (-7075 5175);
DOT 1 (-7325 5350);
DOT 1 (-7550 5350);
DOT 1 (-7550 4950);
DOT 1 (-4475 3450);
DOT 1 (-4475 3075);
DOT 1 (-5075 2000);
DOT 1 (-6250 3075);
DOT 1 (-6250 3450);
DOT 1 (-5075 1200);
DOT 1 (-4875 100);
DOT 1 (-4875 -400);
DOT 1 (-5000 100);
DOT 1 (-5700 350);
FORCENOTE
LOAD-LINE=0.8MINI OHM
(-125 4725) 0;
DISPLAY LEFT (-125 4725);
DISPLAY 0.936170 (-125 4725);
PAINT WHITE (-125 4725);
FORCENOTE
SLEW RATE=8.6A/US(EMR 8A/US)
(-125 4800) 0;
DISPLAY LEFT (-125 4800);
DISPLAY 0.936170 (-125 4800);
PAINT RED (-125 4800);
FORCENOTE
(EMR 20A(10A-30A)
(-150 4875) 0;
DISPLAY LEFT (-150 4875);
DISPLAY 0.936170 (-150 4875);
PAINT RED (-150 4875);
FORCENOTE
CURRENT STEP=17A(8A-25A)
(-125 4950) 0;
DISPLAY LEFT (-125 4950);
DISPLAY 0.936170 (-125 4950);
PAINT RED (-125 4950);
FORCENOTE
MAX CURRENT=25A(EMR 30A)
(-125 5100) 0;
DISPLAY LEFT (-125 5100);
DISPLAY 0.936170 (-125 5100);
PAINT RED (-125 5100);
FORCENOTE
(FUTURE 1.189VMX/1.081VMIN)
(-150 5250) 0;
DISPLAY LEFT (-150 5250);
DISPLAY 0.936170 (-150 5250);
PAINT RED (-150 5250);
FORCENOTE
TOTAL TOLERANCE=1.192MAX/1.086VMIN
(-125 5325) 0;
DISPLAY LEFT (-125 5325);
DISPLAY 0.936170 (-125 5325);
PAINT RED (-125 5325);
FORCENOTE
TDC=23A(EMR 26A)
(-125 5175) 0;
DISPLAY LEFT (-125 5175);
DISPLAY 0.936170 (-125 5175);
PAINT RED (-125 5175);
FORCENOTE
OCP=35A
(-125 5025) 0;
DISPLAY LEFT (-125 5025);
DISPLAY 0.936170 (-125 5025);
PAINT WHITE (-125 5025);
FORCENOTE
CONFIRM ADDRESS SETTING
(-6750 550) 0;
DISPLAY LEFT (-6750 550);
DISPLAY 1.021277 (-6750 550);
PAINT SKYBLUE (-6750 550);
FORCENOTE
SET FW CODE FUNCTION TO BVR_EN
(-5600 1050) 0;
DISPLAY LEFT (-5600 1050);
DISPLAY 1.021277 (-5600 1050);
PAINT SKYBLUE (-5600 1050);
FORCENOTE
76H/ECH
(-6571 -500) 0;
DISPLAY LEFT (-6571 -500);
DISPLAY 0.638298 (-6571 -500);
PAINT WHITE (-6571 -500);
FORCENOTE
I2C(7BIT/8BIT)
(-6571 -400) 0;
DISPLAY LEFT (-6571 -400);
DISPLAY 0.808511 (-6571 -400);
PAINT WHITE (-6571 -400);
FORCENOTE
TRACE SPACING = 5MIL
(-7375 2750) 0;
DISPLAY LEFT (-7375 2750);
DISPLAY 1.021277 (-7375 2750);
PAINT WHITE (-7375 2750);
FORCENOTE
TRACE WIDTH = 10MIL
(-7375 2825) 0;
DISPLAY LEFT (-7375 2825);
DISPLAY 1.021277 (-7375 2825);
PAINT WHITE (-7375 2825);
FORCENOTE
00H
(-6896 -500) 0;
DISPLAY LEFT (-6896 -500);
DISPLAY 0.638298 (-6896 -500);
PAINT WHITE (-6896 -500);
FORCENOTE
SVID
(-6921 -400) 0;
DISPLAY LEFT (-6921 -400);
DISPLAY 0.808511 (-6921 -400);
PAINT WHITE (-6921 -400);
FORCENOTE
RAIL
(-7471 -400) 0;
DISPLAY LEFT (-7471 -400);
DISPLAY 0.808511 (-7471 -400);
PAINT WHITE (-7471 -400);
FORCENOTE
PVCCD_HV_CPU1
(-7596 -500) 0;
DISPLAY LEFT (-7596 -500);
DISPLAY 0.638298 (-7596 -500);
PAINT WHITE (-7596 -500);
FORCENOTE
SVID / I2C ADDRESS
(-7521 -275) 0;
DISPLAY LEFT (-7521 -275);
DISPLAY 1.170213 (-7521 -275);
PAINT WHITE (-7521 -275);
FORCENOTE
PVCCD_HV_CPU1 SPECIFICATION
(-125 5803) 0;
DISPLAY LEFT (-125 5803);
DISPLAY 1.021277 (-125 5803);
PAINT WHITE (-125 5803);
FORCENOTE
VBOOT=1.1V
(-125 5700) 0;
DISPLAY LEFT (-125 5700);
DISPLAY 0.936170 (-125 5700);
PAINT WHITE (-125 5700);
FORCENOTE
WORK FREQUENCY=700KHZ
(-125 4650) 0;
DISPLAY LEFT (-125 4650);
DISPLAY 0.936170 (-125 4650);
PAINT WHITE (-125 4650);
FORCENOTE
SVID ADDRESS=00H BUS#1
(-125 4575) 0;
DISPLAY LEFT (-125 4575);
DISPLAY 0.936170 (-125 4575);
PAINT WHITE (-125 4575);
FORCENOTE
PROTOCOL ID=07H (VR13 5MV VID)
(-125 4500) 0;
DISPLAY LEFT (-125 4500);
DISPLAY 0.936170 (-125 4500);
PAINT WHITE (-125 4500);
FORCENOTE
MAX VR OFFSET=5MV
(-125 5550) 0;
DISPLAY LEFT (-125 5550);
DISPLAY 0.936170 (-125 5550);
PAINT WHITE (-125 5550);
FORCENOTE
DC=+/-0.5% OF VID
(-125 5400) 0;
DISPLAY LEFT (-125 5400);
DISPLAY 0.936170 (-125 5400);
PAINT WHITE (-125 5400);
FORCENOTE
RIPPLE=+/-10MV
(-125 5475) 0;
DISPLAY LEFT (-125 5475);
DISPLAY 0.936170 (-125 5475);
PAINT RED (-125 5475);
FORCENOTE
20220808 UPDATE PDG REV 1.6
(-575 4300) 0;
DISPLAY LEFT (-575 4300);
DISPLAY 1.595745 (-575 4300);
FORCENOTE
PDG REV.1.6 FOR SPR+HBM
(-125 4425) 0;
DISPLAY LEFT (-125 4425);
DISPLAY 0.936170 (-125 4425);
PAINT RED (-125 4425);
FORCENOTE
MAX VOLTAGE VIA BIOS COMMAND=1.145V
(-125 5625) 0;
DISPLAY LEFT (-125 5625);
DISPLAY 0.936170 (-125 5625);
PAINT WHITE (-125 5625);
FORCENOTE
DIFFERENTIAL PAIR
(-7375 2900) 0;
DISPLAY LEFT (-7375 2900);
DISPLAY 1.021277 (-7375 2900);
PAINT WHITE (-7375 2900);
QUIT
